G04 ================== begin FILE IDENTIFICATION RECORD ==================*
G04 Layout Name:  D:/<user>/Wistron_project/16317-1/gbr/16317-1.brd*
G04 Film Name:    TSMD*
G04 File Format:  Gerber RS274X*
G04 File Origin:  Cadence Allegro 16.5-S056*
G04 Origin Date:  Fri Jun 09 15:53:03 2017*
G04 *
G04 Layer:  VIA CLASS/PASTEMASK_TOP*
G04 Layer:  PIN/PASTEMASK_TOP*
G04 Layer:  PACKAGE GEOMETRY/PASTEMASK_TOP*
G04 Layer:  DRAWING FORMAT/LAYER_PCB_STORY*
G04 Layer:  DRAWING FORMAT/LAYER_PAST_T*
G04 Layer:  BOARD GEOMETRY/PANEL_OUTLINE*
G04 *
G04 Offset:    (0.00 0.00)*
G04 Mirror:    No*
G04 Mode:      Positive*
G04 Rotation:  0*
G04 FullContactRelief:  No*
G04 UndefLineWidth:     6.00*
G04 ================== end FILE IDENTIFICATION RECORD ====================*
%FSLAX35Y35*MOIN*%
%IR0*IPPOS*OFA0.00000B0.00000*MIA0B0*SFA1.00000B1.00000*%
%AMMACRO31*
4,1,40,.017,-.013,
.017,.013,
.016939,.013695,
.016759,.014368,
.016464,.015,
.016064,.015571,
.015571,.016064,
.015,.016464,
.014368,.016759,
.013695,.016939,
.013,.017,
-.013,.017,
-.013695,.016939,
-.014368,.016759,
-.015,.016464,
-.015571,.016064,
-.016064,.015571,
-.016464,.015,
-.016759,.014368,
-.016939,.013695,
-.017,.013,
-.017,-.013,
-.016939,-.013695,
-.016759,-.014368,
-.016464,-.015,
-.016064,-.015571,
-.015571,-.016064,
-.015,-.016464,
-.014368,-.016759,
-.013695,-.016939,
-.013,-.017,
.013,-.017,
.013695,-.016939,
.014368,-.016759,
.015,-.016464,
.015571,-.016064,
.016064,-.015571,
.016464,-.015,
.016759,-.014368,
.016939,-.013695,
.017,-.013,
0.0*
%
%ADD31MACRO31*%
%AMMACRO29*
4,1,40,.013,.017,
-.013,.017,
-.013695,.016939,
-.014368,.016759,
-.015,.016464,
-.015571,.016064,
-.016064,.015571,
-.016464,.015,
-.016759,.014368,
-.016939,.013695,
-.017,.013,
-.017,-.013,
-.016939,-.013695,
-.016759,-.014368,
-.016464,-.015,
-.016064,-.015571,
-.015571,-.016064,
-.015,-.016464,
-.014368,-.016759,
-.013695,-.016939,
-.013,-.017,
.013,-.017,
.013695,-.016939,
.014368,-.016759,
.015,-.016464,
.015571,-.016064,
.016064,-.015571,
.016464,-.015,
.016759,-.014368,
.016939,-.013695,
.017,-.013,
.017,.013,
.016939,.013695,
.016759,.014368,
.016464,.015,
.016064,.015571,
.015571,.016064,
.015,.016464,
.014368,.016759,
.013695,.016939,
.013,.017,
0.0*
%
%ADD29MACRO29*%
%ADD58R,.055X.11*%
%ADD60R,.11X.055*%
%ADD70R,.056X.14*%
%ADD59R,.08X.127*%
%ADD10C,.04*%
%ADD78R,.127X.08*%
%ADD46C,.032*%
%AMMACRO43*
4,1,40,-.007,.004,
-.007,-.004,
-.00697,-.004347,
-.006879,-.004684,
-.006732,-.005,
-.006532,-.005286,
-.006286,-.005532,
-.006,-.005732,
-.005684,-.005879,
-.005347,-.00597,
-.005,-.006,
.005,-.006,
.005347,-.00597,
.005684,-.005879,
.006,-.005732,
.006286,-.005532,
.006532,-.005286,
.006732,-.005,
.006879,-.004684,
.00697,-.004347,
.007,-.004,
.007,.004,
.00697,.004347,
.006879,.004684,
.006732,.005,
.006532,.005286,
.006286,.005532,
.006,.005732,
.005684,.005879,
.005347,.00597,
.005,.006,
-.005,.006,
-.005347,.00597,
-.005684,.005879,
-.006,.005732,
-.006286,.005532,
-.006532,.005286,
-.006732,.005,
-.006879,.004684,
-.00697,.004347,
-.007,.004,
0.0*
%
%ADD43MACRO43*%
%ADD62R,.096X.22*%
%ADD83R,.118X.047*%
%ADD23C,.026*%
%ADD77R,.008X.037*%
%ADD76R,.037X.008*%
%ADD82R,.157X.067*%
%AMMACRO40*
4,1,40,.0225,-.007,
.022378,-.008389,
.022018,-.009736,
.021428,-.011,
.020628,-.012142,
.019642,-.013128,
.0185,-.013928,
.017236,-.014518,
.015889,-.014878,
.0145,-.015,
-.0145,-.015,
-.015889,-.014878,
-.017236,-.014518,
-.0185,-.013928,
-.019642,-.013128,
-.020628,-.012142,
-.021428,-.011,
-.022018,-.009736,
-.022378,-.008389,
-.0225,-.007,
-.0225,.007,
-.022378,.008389,
-.022018,.009736,
-.021428,.011,
-.020628,.012142,
-.019642,.013128,
-.0185,.013928,
-.017236,.014518,
-.015889,.014878,
-.0145,.015,
.0145,.015,
.015889,.014878,
.017236,.014518,
.0185,.013928,
.019642,.013128,
.020628,.012142,
.021428,.011,
.022018,.009736,
.022378,.008389,
.0225,.007,
.0225,-.007,
0.0*
%
%ADD40MACRO40*%
%AMMACRO75*
4,1,40,-.007,-.0225,
-.008389,-.022378,
-.009736,-.022018,
-.011,-.021428,
-.012142,-.020628,
-.013128,-.019642,
-.013928,-.0185,
-.014518,-.017236,
-.014878,-.015889,
-.015,-.0145,
-.015,.0145,
-.014878,.015889,
-.014518,.017236,
-.013928,.0185,
-.013128,.019642,
-.012142,.020628,
-.011,.021428,
-.009736,.022018,
-.008389,.022378,
-.007,.0225,
.007,.0225,
.008389,.022378,
.009736,.022018,
.011,.021428,
.012142,.020628,
.013128,.019642,
.013928,.0185,
.014518,.017236,
.014878,.015889,
.015,.0145,
.015,-.0145,
.014878,-.015889,
.014518,-.017236,
.013928,-.0185,
.013128,-.019642,
.012142,-.020628,
.011,-.021428,
.009736,-.022018,
.008389,-.022378,
.007,-.0225,
-.007,-.0225,
0.0*
%
%ADD75MACRO75*%
%AMMACRO16*
4,1,40,.011,-.007,
.011,.007,
.010939,.007695,
.010759,.008368,
.010464,.009,
.010064,.009571,
.009571,.010064,
.009,.010464,
.008368,.010759,
.007695,.010939,
.007,.011,
-.007,.011,
-.007695,.010939,
-.008368,.010759,
-.009,.010464,
-.009571,.010064,
-.010064,.009571,
-.010464,.009,
-.010759,.008368,
-.010939,.007695,
-.011,.007,
-.011,-.007,
-.010939,-.007695,
-.010759,-.008368,
-.010464,-.009,
-.010064,-.009571,
-.009571,-.010064,
-.009,-.010464,
-.008368,-.010759,
-.007695,-.010939,
-.007,-.011,
.007,-.011,
.007695,-.010939,
.008368,-.010759,
.009,-.010464,
.009571,-.010064,
.010064,-.009571,
.010464,-.009,
.010759,-.008368,
.010939,-.007695,
.011,-.007,
0.0*
%
%ADD16MACRO16*%
%AMMACRO14*
4,1,40,.007,.011,
-.007,.011,
-.007695,.010939,
-.008368,.010759,
-.009,.010464,
-.009571,.010064,
-.010064,.009571,
-.010464,.009,
-.010759,.008368,
-.010939,.007695,
-.011,.007,
-.011,-.007,
-.010939,-.007695,
-.010759,-.008368,
-.010464,-.009,
-.010064,-.009571,
-.009571,-.010064,
-.009,-.010464,
-.008368,-.010759,
-.007695,-.010939,
-.007,-.011,
.007,-.011,
.007695,-.010939,
.008368,-.010759,
.009,-.010464,
.009571,-.010064,
.010064,-.009571,
.010464,-.009,
.010759,-.008368,
.010939,-.007695,
.011,-.007,
.011,.007,
.010939,.007695,
.010759,.008368,
.010464,.009,
.010064,.009571,
.009571,.010064,
.009,.010464,
.008368,.010759,
.007695,.010939,
.007,.011,
0.0*
%
%ADD14MACRO14*%
%AMMACRO27*
4,1,40,-.012,.008,
-.012,-.008,
-.011939,-.008695,
-.011759,-.009368,
-.011464,-.01,
-.011064,-.010571,
-.010571,-.011064,
-.01,-.011464,
-.009368,-.011759,
-.008695,-.011939,
-.008,-.012,
.008,-.012,
.008695,-.011939,
.009368,-.011759,
.01,-.011464,
.010571,-.011064,
.011064,-.010571,
.011464,-.01,
.011759,-.009368,
.011939,-.008695,
.012,-.008,
.012,.008,
.011939,.008695,
.011759,.009368,
.011464,.01,
.011064,.010571,
.010571,.011064,
.01,.011464,
.009368,.011759,
.008695,.011939,
.008,.012,
-.008,.012,
-.008695,.011939,
-.009368,.011759,
-.01,.011464,
-.010571,.011064,
-.011064,.010571,
-.011464,.01,
-.011759,.009368,
-.011939,.008695,
-.012,.008,
0.0*
%
%ADD27MACRO27*%
%AMMACRO49*
4,1,40,.008,.012,
-.008,.012,
-.008695,.011939,
-.009368,.011759,
-.01,.011464,
-.010571,.011064,
-.011064,.010571,
-.011464,.01,
-.011759,.009368,
-.011939,.008695,
-.012,.008,
-.012,-.008,
-.011939,-.008695,
-.011759,-.009368,
-.011464,-.01,
-.011064,-.010571,
-.010571,-.011064,
-.01,-.011464,
-.009368,-.011759,
-.008695,-.011939,
-.008,-.012,
.008,-.012,
.008695,-.011939,
.009368,-.011759,
.01,-.011464,
.010571,-.011064,
.011064,-.010571,
.011464,-.01,
.011759,-.009368,
.011939,-.008695,
.012,-.008,
.012,.008,
.011939,.008695,
.011759,.009368,
.011464,.01,
.011064,.010571,
.010571,.011064,
.01,.011464,
.009368,.011759,
.008695,.011939,
.008,.012,
0.0*
%
%ADD49MACRO49*%
%AMMACRO44*
4,1,40,-.013,-.017,
.013,-.017,
.013695,-.016939,
.014368,-.016759,
.015,-.016464,
.015571,-.016064,
.016064,-.015571,
.016464,-.015,
.016759,-.014368,
.016939,-.013695,
.017,-.013,
.017,.013,
.016939,.013695,
.016759,.014368,
.016464,.015,
.016064,.015571,
.015571,.016064,
.015,.016464,
.014368,.016759,
.013695,.016939,
.013,.017,
-.013,.017,
-.013695,.016939,
-.014368,.016759,
-.015,.016464,
-.015571,.016064,
-.016064,.015571,
-.016464,.015,
-.016759,.014368,
-.016939,.013695,
-.017,.013,
-.017,-.013,
-.016939,-.013695,
-.016759,-.014368,
-.016464,-.015,
-.016064,-.015571,
-.015571,-.016064,
-.015,-.016464,
-.014368,-.016759,
-.013695,-.016939,
-.013,-.017,
0.0*
%
%ADD44MACRO44*%
%AMMACRO37*
4,1,40,-.017,.013,
-.017,-.013,
-.016939,-.013695,
-.016759,-.014368,
-.016464,-.015,
-.016064,-.015571,
-.015571,-.016064,
-.015,-.016464,
-.014368,-.016759,
-.013695,-.016939,
-.013,-.017,
.013,-.017,
.013695,-.016939,
.014368,-.016759,
.015,-.016464,
.015571,-.016064,
.016064,-.015571,
.016464,-.015,
.016759,-.014368,
.016939,-.013695,
.017,-.013,
.017,.013,
.016939,.013695,
.016759,.014368,
.016464,.015,
.016064,.015571,
.015571,.016064,
.015,.016464,
.014368,.016759,
.013695,.016939,
.013,.017,
-.013,.017,
-.013695,.016939,
-.014368,.016759,
-.015,.016464,
-.015571,.016064,
-.016064,.015571,
-.016464,.015,
-.016759,.014368,
-.016939,.013695,
-.017,.013,
0.0*
%
%ADD37MACRO37*%
%AMMACRO17*
4,1,40,.011,-.007,
.011,.007,
.010939,.007695,
.010759,.008368,
.010464,.009,
.010064,.009571,
.009571,.010064,
.009,.010464,
.008368,.010759,
.007695,.010939,
.007,.011,
-.007,.011,
-.007695,.010939,
-.008368,.010759,
-.009,.010464,
-.009571,.010064,
-.010064,.009571,
-.010464,.009,
-.010759,.008368,
-.010939,.007695,
-.011,.007,
-.011,-.007,
-.010939,-.007695,
-.010759,-.008368,
-.010464,-.009,
-.010064,-.009571,
-.009571,-.010064,
-.009,-.010464,
-.008368,-.010759,
-.007695,-.010939,
-.007,-.011,
.007,-.011,
.007695,-.010939,
.008368,-.010759,
.009,-.010464,
.009571,-.010064,
.010064,-.009571,
.010464,-.009,
.010759,-.008368,
.010939,-.007695,
.011,-.007,
0.0*
%
%ADD17MACRO17*%
%AMMACRO15*
4,1,40,.007,.011,
-.007,.011,
-.007695,.010939,
-.008368,.010759,
-.009,.010464,
-.009571,.010064,
-.010064,.009571,
-.010464,.009,
-.010759,.008368,
-.010939,.007695,
-.011,.007,
-.011,-.007,
-.010939,-.007695,
-.010759,-.008368,
-.010464,-.009,
-.010064,-.009571,
-.009571,-.010064,
-.009,-.010464,
-.008368,-.010759,
-.007695,-.010939,
-.007,-.011,
.007,-.011,
.007695,-.010939,
.008368,-.010759,
.009,-.010464,
.009571,-.010064,
.010064,-.009571,
.010464,-.009,
.010759,-.008368,
.010939,-.007695,
.011,-.007,
.011,.007,
.010939,.007695,
.010759,.008368,
.010464,.009,
.010064,.009571,
.009571,.010064,
.009,.010464,
.008368,.010759,
.007695,.010939,
.007,.011,
0.0*
%
%ADD15MACRO15*%
%AMMACRO26*
4,1,40,-.012,.008,
-.012,-.008,
-.011939,-.008695,
-.011759,-.009368,
-.011464,-.01,
-.011064,-.010571,
-.010571,-.011064,
-.01,-.011464,
-.009368,-.011759,
-.008695,-.011939,
-.008,-.012,
.008,-.012,
.008695,-.011939,
.009368,-.011759,
.01,-.011464,
.010571,-.011064,
.011064,-.010571,
.011464,-.01,
.011759,-.009368,
.011939,-.008695,
.012,-.008,
.012,.008,
.011939,.008695,
.011759,.009368,
.011464,.01,
.011064,.010571,
.010571,.011064,
.01,.011464,
.009368,.011759,
.008695,.011939,
.008,.012,
-.008,.012,
-.008695,.011939,
-.009368,.011759,
-.01,.011464,
-.010571,.011064,
-.011064,.010571,
-.011464,.01,
-.011759,.009368,
-.011939,.008695,
-.012,.008,
0.0*
%
%ADD26MACRO26*%
%AMMACRO48*
4,1,40,.008,.012,
-.008,.012,
-.008695,.011939,
-.009368,.011759,
-.01,.011464,
-.010571,.011064,
-.011064,.010571,
-.011464,.01,
-.011759,.009368,
-.011939,.008695,
-.012,.008,
-.012,-.008,
-.011939,-.008695,
-.011759,-.009368,
-.011464,-.01,
-.011064,-.010571,
-.010571,-.011064,
-.01,-.011464,
-.009368,-.011759,
-.008695,-.011939,
-.008,-.012,
.008,-.012,
.008695,-.011939,
.009368,-.011759,
.01,-.011464,
.010571,-.011064,
.011064,-.010571,
.011464,-.01,
.011759,-.009368,
.011939,-.008695,
.012,-.008,
.012,.008,
.011939,.008695,
.011759,.009368,
.011464,.01,
.011064,.010571,
.010571,.011064,
.01,.011464,
.009368,.011759,
.008695,.011939,
.008,.012,
0.0*
%
%ADD48MACRO48*%
%AMMACRO45*
4,1,40,-.013,-.017,
.013,-.017,
.013695,-.016939,
.014368,-.016759,
.015,-.016464,
.015571,-.016064,
.016064,-.015571,
.016464,-.015,
.016759,-.014368,
.016939,-.013695,
.017,-.013,
.017,.013,
.016939,.013695,
.016759,.014368,
.016464,.015,
.016064,.015571,
.015571,.016064,
.015,.016464,
.014368,.016759,
.013695,.016939,
.013,.017,
-.013,.017,
-.013695,.016939,
-.014368,.016759,
-.015,.016464,
-.015571,.016064,
-.016064,.015571,
-.016464,.015,
-.016759,.014368,
-.016939,.013695,
-.017,.013,
-.017,-.013,
-.016939,-.013695,
-.016759,-.014368,
-.016464,-.015,
-.016064,-.015571,
-.015571,-.016064,
-.015,-.016464,
-.014368,-.016759,
-.013695,-.016939,
-.013,-.017,
0.0*
%
%ADD45MACRO45*%
%AMMACRO38*
4,1,40,-.017,.013,
-.017,-.013,
-.016939,-.013695,
-.016759,-.014368,
-.016464,-.015,
-.016064,-.015571,
-.015571,-.016064,
-.015,-.016464,
-.014368,-.016759,
-.013695,-.016939,
-.013,-.017,
.013,-.017,
.013695,-.016939,
.014368,-.016759,
.015,-.016464,
.015571,-.016064,
.016064,-.015571,
.016464,-.015,
.016759,-.014368,
.016939,-.013695,
.017,-.013,
.017,.013,
.016939,.013695,
.016759,.014368,
.016464,.015,
.016064,.015571,
.015571,.016064,
.015,.016464,
.014368,.016759,
.013695,.016939,
.013,.017,
-.013,.017,
-.013695,.016939,
-.014368,.016759,
-.015,.016464,
-.015571,.016064,
-.016064,.015571,
-.016464,.015,
-.016759,.014368,
-.016939,.013695,
-.017,.013,
0.0*
%
%ADD38MACRO38*%
%ADD57R,.04X.022*%
%ADD81R,.02X.06*%
%ADD73R,.06X.03*%
%ADD21R,.022X.04*%
%ADD84R,.142X.106*%
%ADD68R,.012X.042*%
%ADD66R,.042X.012*%
%ADD71R,.06X.014*%
%ADD53R,.04X.016*%
%ADD56R,.032X.016*%
%ADD47R,.014X.06*%
%ADD22R,.016X.04*%
%ADD87R,.016X.032*%
%ADD74R,.06X.016*%
%ADD67R,.012X.036*%
%ADD65R,.036X.012*%
%AMMACRO85*
4,1,40,.007,-.004,
.007,.004,
.00697,.004347,
.006879,.004684,
.006732,.005,
.006532,.005286,
.006286,.005532,
.006,.005732,
.005684,.005879,
.005347,.00597,
.005,.006,
-.005,.006,
-.005347,.00597,
-.005684,.005879,
-.006,.005732,
-.006286,.005532,
-.006532,.005286,
-.006732,.005,
-.006879,.004684,
-.00697,.004347,
-.007,.004,
-.007,-.004,
-.00697,-.004347,
-.006879,-.004684,
-.006732,-.005,
-.006532,-.005286,
-.006286,-.005532,
-.006,-.005732,
-.005684,-.005879,
-.005347,-.00597,
-.005,-.006,
.005,-.006,
.005347,-.00597,
.005684,-.005879,
.006,-.005732,
.006286,-.005532,
.006532,-.005286,
.006732,-.005,
.006879,-.004684,
.00697,-.004347,
.007,-.004,
0.0*
%
%ADD85MACRO85*%
%ADD11R,.093X.02*%
%ADD32R,.05X.065*%
%ADD33R,.065X.05*%
%ADD86R,.065X.025*%
%ADD54R,.055X.035*%
%ADD41R,.093X.024*%
%ADD36R,.028X.034*%
%ADD61R,.035X.055*%
%ADD52R,.048X.016*%
%ADD42R,.102X.102*%
%ADD34R,.045X.055*%
%ADD20R,.025X.065*%
%ADD69R,.13X.13*%
%ADD55R,.016X.048*%
%ADD35R,.055X.045*%
%ADD72R,.073X.047*%
%AMMACRO80*
4,1,46,.00177,.018,
.003163,.017918,
.00452,.017595,
.0058,.017042,
.006965,.016274,
.007979,.015316,
.008812,.014196,
.009437,.012949,
.009836,.011613,
.009997,.010227,
.01,.01,
.01,-.01,
.00999,-.01,
.009868,-.011389,
.009507,-.012737,
.008918,-.014001,
.008118,-.015143,
.007132,-.016129,
.005989,-.016929,
.004725,-.017519,
.003378,-.01788,
.001989,-.018001,
.00185,-.018,
-.00185,-.018,
-.003241,-.017903,
-.004595,-.017565,
-.005869,-.016998,
-.007025,-.016218,
-.008028,-.015249,
-.008848,-.01412,
-.009459,-.012867,
-.009843,-.011526,
-.009989,-.010139,
-.00999,-.01,
-.01,-.01,
-.01,.01,
-.009878,.01139,
-.009517,.012737,
-.008928,.014002,
-.008128,.015144,
-.007141,.016131,
-.005998,.016931,
-.004734,.017521,
-.003387,.017882,
-.001997,.018003,
-.00177,.018,
.00177,.018,
0.0*
%
%ADD80MACRO80*%
%ADD79R,.09X.095*%
%AMMACRO64*
4,1,40,-.0225,.007,
-.022378,.008389,
-.022018,.009736,
-.021428,.011,
-.020628,.012142,
-.019642,.013128,
-.0185,.013928,
-.017236,.014518,
-.015889,.014878,
-.0145,.015,
.0145,.015,
.015889,.014878,
.017236,.014518,
.0185,.013928,
.019642,.013128,
.020628,.012142,
.021428,.011,
.022018,.009736,
.022378,.008389,
.0225,.007,
.0225,-.007,
.022378,-.008389,
.022018,-.009736,
.021428,-.011,
.020628,-.012142,
.019642,-.013128,
.0185,-.013928,
.017236,-.014518,
.015889,-.014878,
.0145,-.015,
-.0145,-.015,
-.015889,-.014878,
-.017236,-.014518,
-.0185,-.013928,
-.019642,-.013128,
-.020628,-.012142,
-.021428,-.011,
-.022018,-.009736,
-.022378,-.008389,
-.0225,-.007,
-.0225,.007,
0.0*
%
%ADD64MACRO64*%
%ADD63R,.096X.035*%
%AMMACRO39*
4,1,40,.007,.0225,
.008389,.022378,
.009736,.022018,
.011,.021428,
.012142,.020628,
.013128,.019642,
.013928,.0185,
.014518,.017236,
.014878,.015889,
.015,.0145,
.015,-.0145,
.014878,-.015889,
.014518,-.017236,
.013928,-.0185,
.013128,-.019642,
.012142,-.020628,
.011,-.021428,
.009736,-.022018,
.008389,-.022378,
.007,-.0225,
-.007,-.0225,
-.008389,-.022378,
-.009736,-.022018,
-.011,-.021428,
-.012142,-.020628,
-.013128,-.019642,
-.013928,-.0185,
-.014518,-.017236,
-.014878,-.015889,
-.015,-.0145,
-.015,.0145,
-.014878,.015889,
-.014518,.017236,
-.013928,.0185,
-.013128,.019642,
-.012142,.020628,
-.011,.021428,
-.009736,.022018,
-.008389,.022378,
-.007,.0225,
.007,.0225,
0.0*
%
%ADD39MACRO39*%
%AMMACRO51*
4,1,40,-.008,-.012,
.008,-.012,
.008695,-.011939,
.009368,-.011759,
.01,-.011464,
.010571,-.011064,
.011064,-.010571,
.011464,-.01,
.011759,-.009368,
.011939,-.008695,
.012,-.008,
.012,.008,
.011939,.008695,
.011759,.009368,
.011464,.01,
.011064,.010571,
.010571,.011064,
.01,.011464,
.009368,.011759,
.008695,.011939,
.008,.012,
-.008,.012,
-.008695,.011939,
-.009368,.011759,
-.01,.011464,
-.010571,.011064,
-.011064,.010571,
-.011464,.01,
-.011759,.009368,
-.011939,.008695,
-.012,.008,
-.012,-.008,
-.011939,-.008695,
-.011759,-.009368,
-.011464,-.01,
-.011064,-.010571,
-.010571,-.011064,
-.01,-.011464,
-.009368,-.011759,
-.008695,-.011939,
-.008,-.012,
0.0*
%
%ADD51MACRO51*%
%AMMACRO25*
4,1,40,.012,-.008,
.012,.008,
.011939,.008695,
.011759,.009368,
.011464,.01,
.011064,.010571,
.010571,.011064,
.01,.011464,
.009368,.011759,
.008695,.011939,
.008,.012,
-.008,.012,
-.008695,.011939,
-.009368,.011759,
-.01,.011464,
-.010571,.011064,
-.011064,.010571,
-.011464,.01,
-.011759,.009368,
-.011939,.008695,
-.012,.008,
-.012,-.008,
-.011939,-.008695,
-.011759,-.009368,
-.011464,-.01,
-.011064,-.010571,
-.010571,-.011064,
-.01,-.011464,
-.009368,-.011759,
-.008695,-.011939,
-.008,-.012,
.008,-.012,
.008695,-.011939,
.009368,-.011759,
.01,-.011464,
.010571,-.011064,
.011064,-.010571,
.011464,-.01,
.011759,-.009368,
.011939,-.008695,
.012,-.008,
0.0*
%
%ADD25MACRO25*%
%AMMACRO12*
4,1,40,-.007,-.011,
.007,-.011,
.007695,-.010939,
.008368,-.010759,
.009,-.010464,
.009571,-.010064,
.010064,-.009571,
.010464,-.009,
.010759,-.008368,
.010939,-.007695,
.011,-.007,
.011,.007,
.010939,.007695,
.010759,.008368,
.010464,.009,
.010064,.009571,
.009571,.010064,
.009,.010464,
.008368,.010759,
.007695,.010939,
.007,.011,
-.007,.011,
-.007695,.010939,
-.008368,.010759,
-.009,.010464,
-.009571,.010064,
-.010064,.009571,
-.010464,.009,
-.010759,.008368,
-.010939,.007695,
-.011,.007,
-.011,-.007,
-.010939,-.007695,
-.010759,-.008368,
-.010464,-.009,
-.010064,-.009571,
-.009571,-.010064,
-.009,-.010464,
-.008368,-.010759,
-.007695,-.010939,
-.007,-.011,
0.0*
%
%ADD12MACRO12*%
%AMMACRO18*
4,1,40,-.011,.007,
-.011,-.007,
-.010939,-.007695,
-.010759,-.008368,
-.010464,-.009,
-.010064,-.009571,
-.009571,-.010064,
-.009,-.010464,
-.008368,-.010759,
-.007695,-.010939,
-.007,-.011,
.007,-.011,
.007695,-.010939,
.008368,-.010759,
.009,-.010464,
.009571,-.010064,
.010064,-.009571,
.010464,-.009,
.010759,-.008368,
.010939,-.007695,
.011,-.007,
.011,.007,
.010939,.007695,
.010759,.008368,
.010464,.009,
.010064,.009571,
.009571,.010064,
.009,.010464,
.008368,.010759,
.007695,.010939,
.007,.011,
-.007,.011,
-.007695,.010939,
-.008368,.010759,
-.009,.010464,
-.009571,.010064,
-.010064,.009571,
-.010464,.009,
-.010759,.008368,
-.010939,.007695,
-.011,.007,
0.0*
%
%ADD18MACRO18*%
%AMMACRO30*
4,1,40,.017,-.013,
.017,.013,
.016939,.013695,
.016759,.014368,
.016464,.015,
.016064,.015571,
.015571,.016064,
.015,.016464,
.014368,.016759,
.013695,.016939,
.013,.017,
-.013,.017,
-.013695,.016939,
-.014368,.016759,
-.015,.016464,
-.015571,.016064,
-.016064,.015571,
-.016464,.015,
-.016759,.014368,
-.016939,.013695,
-.017,.013,
-.017,-.013,
-.016939,-.013695,
-.016759,-.014368,
-.016464,-.015,
-.016064,-.015571,
-.015571,-.016064,
-.015,-.016464,
-.014368,-.016759,
-.013695,-.016939,
-.013,-.017,
.013,-.017,
.013695,-.016939,
.014368,-.016759,
.015,-.016464,
.015571,-.016064,
.016064,-.015571,
.016464,-.015,
.016759,-.014368,
.016939,-.013695,
.017,-.013,
0.0*
%
%ADD30MACRO30*%
%AMMACRO28*
4,1,40,.013,.017,
-.013,.017,
-.013695,.016939,
-.014368,.016759,
-.015,.016464,
-.015571,.016064,
-.016064,.015571,
-.016464,.015,
-.016759,.014368,
-.016939,.013695,
-.017,.013,
-.017,-.013,
-.016939,-.013695,
-.016759,-.014368,
-.016464,-.015,
-.016064,-.015571,
-.015571,-.016064,
-.015,-.016464,
-.014368,-.016759,
-.013695,-.016939,
-.013,-.017,
.013,-.017,
.013695,-.016939,
.014368,-.016759,
.015,-.016464,
.015571,-.016064,
.016064,-.015571,
.016464,-.015,
.016759,-.014368,
.016939,-.013695,
.017,-.013,
.017,.013,
.016939,.013695,
.016759,.014368,
.016464,.015,
.016064,.015571,
.015571,.016064,
.015,.016464,
.014368,.016759,
.013695,.016939,
.013,.017,
0.0*
%
%ADD28MACRO28*%
%AMMACRO50*
4,1,40,-.008,-.012,
.008,-.012,
.008695,-.011939,
.009368,-.011759,
.01,-.011464,
.010571,-.011064,
.011064,-.010571,
.011464,-.01,
.011759,-.009368,
.011939,-.008695,
.012,-.008,
.012,.008,
.011939,.008695,
.011759,.009368,
.011464,.01,
.011064,.010571,
.010571,.011064,
.01,.011464,
.009368,.011759,
.008695,.011939,
.008,.012,
-.008,.012,
-.008695,.011939,
-.009368,.011759,
-.01,.011464,
-.010571,.011064,
-.011064,.010571,
-.011464,.01,
-.011759,.009368,
-.011939,.008695,
-.012,.008,
-.012,-.008,
-.011939,-.008695,
-.011759,-.009368,
-.011464,-.01,
-.011064,-.010571,
-.010571,-.011064,
-.01,-.011464,
-.009368,-.011759,
-.008695,-.011939,
-.008,-.012,
0.0*
%
%ADD50MACRO50*%
%AMMACRO24*
4,1,40,.012,-.008,
.012,.008,
.011939,.008695,
.011759,.009368,
.011464,.01,
.011064,.010571,
.010571,.011064,
.01,.011464,
.009368,.011759,
.008695,.011939,
.008,.012,
-.008,.012,
-.008695,.011939,
-.009368,.011759,
-.01,.011464,
-.010571,.011064,
-.011064,.010571,
-.011464,.01,
-.011759,.009368,
-.011939,.008695,
-.012,.008,
-.012,-.008,
-.011939,-.008695,
-.011759,-.009368,
-.011464,-.01,
-.011064,-.010571,
-.010571,-.011064,
-.01,-.011464,
-.009368,-.011759,
-.008695,-.011939,
-.008,-.012,
.008,-.012,
.008695,-.011939,
.009368,-.011759,
.01,-.011464,
.010571,-.011064,
.011064,-.010571,
.011464,-.01,
.011759,-.009368,
.011939,-.008695,
.012,-.008,
0.0*
%
%ADD24MACRO24*%
%AMMACRO13*
4,1,40,-.007,-.011,
.007,-.011,
.007695,-.010939,
.008368,-.010759,
.009,-.010464,
.009571,-.010064,
.010064,-.009571,
.010464,-.009,
.010759,-.008368,
.010939,-.007695,
.011,-.007,
.011,.007,
.010939,.007695,
.010759,.008368,
.010464,.009,
.010064,.009571,
.009571,.010064,
.009,.010464,
.008368,.010759,
.007695,.010939,
.007,.011,
-.007,.011,
-.007695,.010939,
-.008368,.010759,
-.009,.010464,
-.009571,.010064,
-.010064,.009571,
-.010464,.009,
-.010759,.008368,
-.010939,.007695,
-.011,.007,
-.011,-.007,
-.010939,-.007695,
-.010759,-.008368,
-.010464,-.009,
-.010064,-.009571,
-.009571,-.010064,
-.009,-.010464,
-.008368,-.010759,
-.007695,-.010939,
-.007,-.011,
0.0*
%
%ADD13MACRO13*%
%AMMACRO19*
4,1,40,-.011,.007,
-.011,-.007,
-.010939,-.007695,
-.010759,-.008368,
-.010464,-.009,
-.010064,-.009571,
-.009571,-.010064,
-.009,-.010464,
-.008368,-.010759,
-.007695,-.010939,
-.007,-.011,
.007,-.011,
.007695,-.010939,
.008368,-.010759,
.009,-.010464,
.009571,-.010064,
.010064,-.009571,
.010464,-.009,
.010759,-.008368,
.010939,-.007695,
.011,-.007,
.011,.007,
.010939,.007695,
.010759,.008368,
.010464,.009,
.010064,.009571,
.009571,.010064,
.009,.010464,
.008368,.010759,
.007695,.010939,
.007,.011,
-.007,.011,
-.007695,.010939,
-.008368,.010759,
-.009,.010464,
-.009571,.010064,
-.010064,.009571,
-.010464,.009,
-.010759,.008368,
-.010939,.007695,
-.011,.007,
0.0*
%
%ADD19MACRO19*%
%ADD88C,.02*%
%ADD89C,.006*%
G75*
%LPD*%
G75*
G36*
G01X804631Y1313985D02*
Y1322985D01*
X796031D01*
Y1313985D01*
X804631D01*
G37*
G36*
G01Y1302185D02*
Y1311185D01*
X796031D01*
Y1302185D01*
X804631D01*
G37*
G36*
G01X793231D02*
Y1311185D01*
X784631D01*
Y1302185D01*
X793231D01*
G37*
G36*
G01Y1313985D02*
Y1322985D01*
X784631D01*
Y1313985D01*
X793231D01*
G37*
G36*
G01X805101Y1356491D02*
Y1365491D01*
X796501D01*
Y1356491D01*
X805101D01*
G37*
G36*
G01Y1344691D02*
Y1353691D01*
X796501D01*
Y1344691D01*
X805101D01*
G37*
G36*
G01X793701D02*
Y1353691D01*
X785101D01*
Y1344691D01*
X793701D01*
G37*
G36*
G01Y1356491D02*
Y1365491D01*
X785101D01*
Y1356491D01*
X793701D01*
G37*
G36*
G01X804880Y1394159D02*
Y1403159D01*
X796280D01*
Y1394159D01*
X804880D01*
G37*
G36*
G01Y1382359D02*
Y1391359D01*
X796280D01*
Y1382359D01*
X804880D01*
G37*
G36*
G01X793480D02*
Y1391359D01*
X784880D01*
Y1382359D01*
X793480D01*
G37*
G36*
G01Y1394159D02*
Y1403159D01*
X784880D01*
Y1394159D01*
X793480D01*
G37*
G36*
G01X1023118Y1321389D02*
Y1330389D01*
X1014518D01*
Y1321389D01*
X1023118D01*
G37*
G36*
G01Y1309589D02*
Y1318589D01*
X1014518D01*
Y1309589D01*
X1023118D01*
G37*
G36*
G01X1011718D02*
Y1318589D01*
X1003118D01*
Y1309589D01*
X1011718D01*
G37*
G36*
G01Y1321389D02*
Y1330389D01*
X1003118D01*
Y1321389D01*
X1011718D01*
G37*
G36*
G01X1023118Y1376989D02*
Y1385989D01*
X1014518D01*
Y1376989D01*
X1023118D01*
G37*
G36*
G01Y1365189D02*
Y1374189D01*
X1014518D01*
Y1365189D01*
X1023118D01*
G37*
G36*
G01X1011718D02*
Y1374189D01*
X1003118D01*
Y1365189D01*
X1011718D01*
G37*
G36*
G01Y1376989D02*
Y1385989D01*
X1003118D01*
Y1376989D01*
X1011718D01*
G37*
G36*
G01X1023118Y1349189D02*
Y1358189D01*
X1014518D01*
Y1349189D01*
X1023118D01*
G37*
G36*
G01Y1337389D02*
Y1346389D01*
X1014518D01*
Y1337389D01*
X1023118D01*
G37*
G36*
G01X1011718D02*
Y1346389D01*
X1003118D01*
Y1337389D01*
X1011718D01*
G37*
G36*
G01Y1349189D02*
Y1358189D01*
X1003118D01*
Y1349189D01*
X1011718D01*
G37*
G54D10*
X34900Y34200D03*
X40600Y1464400D03*
X1894200Y1471300D03*
G54D20*
X89000Y93500D03*
X84000D03*
X79000D03*
X74000D03*
Y113500D03*
X79000D03*
X84000D03*
X89000D03*
X51000Y131500D03*
X56000D03*
X61000D03*
X66000D03*
Y111500D03*
X61000D03*
X56000D03*
X51000D03*
X89000Y546000D03*
X84000D03*
X79000D03*
X74000D03*
Y566000D03*
X79000D03*
X84000D03*
X89000D03*
X66000Y564000D03*
X61000D03*
X56000D03*
X51000D03*
Y584000D03*
X56000D03*
X61000D03*
X66000D03*
X89000Y999000D03*
X84000D03*
X79000D03*
X74000D03*
Y1019000D03*
X79000D03*
X84000D03*
X89000D03*
X51000Y1037000D03*
X56000D03*
X61000D03*
X66000D03*
Y1017000D03*
X61000D03*
X56000D03*
X51000D03*
X188500Y86000D03*
X183500D03*
X178500D03*
X173500D03*
Y106000D03*
X178500D03*
X183500D03*
X188500D03*
X190000Y564000D03*
X185000D03*
X180000D03*
X175000D03*
Y584000D03*
X180000D03*
X185000D03*
X190000D03*
X175500Y1037000D03*
X180500D03*
X185500D03*
X190500D03*
Y1017000D03*
X185500D03*
X180500D03*
X175500D03*
X194174Y1430800D03*
Y1410800D03*
X213000Y93500D03*
X208000D03*
X203000D03*
X198000D03*
Y113500D03*
X203000D03*
X208000D03*
X213000D03*
Y546000D03*
X208000D03*
X203000D03*
X198000D03*
Y566000D03*
X203000D03*
X208000D03*
X213000D03*
X213500Y999000D03*
X208500D03*
X203500D03*
X198500D03*
Y1019000D03*
X203500D03*
X208500D03*
X213500D03*
X199174Y1430800D03*
X204174D03*
X209174D03*
Y1410800D03*
X204174D03*
X199174D03*
X337500Y93500D03*
X332500D03*
X327500D03*
X322500D03*
Y113500D03*
X327500D03*
X332500D03*
X337500D03*
X299500Y131500D03*
X304500D03*
X309500D03*
X314500D03*
Y111500D03*
X309500D03*
X304500D03*
X299500D03*
X337500Y546000D03*
X332500D03*
X327500D03*
X322500D03*
Y566000D03*
X327500D03*
X332500D03*
X337500D03*
X314500Y564000D03*
X309500D03*
X304500D03*
X299500D03*
Y584000D03*
X304500D03*
X309500D03*
X314500D03*
X337500Y999000D03*
X332500D03*
X327500D03*
X322500D03*
Y1019000D03*
X327500D03*
X332500D03*
X337500D03*
X299500Y1037000D03*
X304500D03*
X309500D03*
X314500D03*
Y1017000D03*
X309500D03*
X304500D03*
X299500D03*
X425500Y66600D03*
X430500D03*
X435500D03*
X440500D03*
Y46600D03*
X435500D03*
X430500D03*
X425500D03*
X461900Y97100D03*
X456900D03*
X451900D03*
X446900D03*
Y117100D03*
X451900D03*
X456900D03*
X461900D03*
X461500Y546000D03*
X456500D03*
X451500D03*
X446500D03*
Y566000D03*
X451500D03*
X456500D03*
X461500D03*
X438500Y564000D03*
X433500D03*
X428500D03*
X423500D03*
Y584000D03*
X428500D03*
X433500D03*
X438500D03*
X461500Y999000D03*
X456500D03*
X451500D03*
X446500D03*
Y1019000D03*
X451500D03*
X456500D03*
X461500D03*
X423500Y1037000D03*
X428500D03*
X433500D03*
X438500D03*
Y1017000D03*
X433500D03*
X428500D03*
X423500D03*
X576000Y93500D03*
X571000D03*
Y113500D03*
X576000D03*
X548000Y131500D03*
X553000D03*
X558000D03*
X563000D03*
Y111500D03*
X558000D03*
X553000D03*
X548000D03*
X576000Y546000D03*
X571000D03*
Y566000D03*
X576000D03*
X563000Y564000D03*
X558000D03*
X553000D03*
X548000D03*
Y584000D03*
X553000D03*
X558000D03*
X563000D03*
X576000Y999000D03*
X571000D03*
Y1019000D03*
X576000D03*
X548000Y1037000D03*
X553000D03*
X558000D03*
X563000D03*
Y1017000D03*
X558000D03*
X553000D03*
X548000D03*
X518035Y1418131D03*
X513035D03*
X508035D03*
X503035D03*
Y1438131D03*
X508035D03*
X513035D03*
X518035D03*
X586000Y93500D03*
X581000D03*
X670500Y86000D03*
X581000Y113500D03*
X586000D03*
X670500Y106000D03*
X586000Y546000D03*
X581000D03*
Y566000D03*
X586000D03*
X672000Y564000D03*
Y584000D03*
X586000Y999000D03*
X581000D03*
Y1019000D03*
X586000D03*
X672000Y1037000D03*
Y1017000D03*
X710000Y93500D03*
X705000D03*
X700000D03*
X695000D03*
X685500Y86000D03*
X680500D03*
X675500D03*
X695000Y113500D03*
X700000D03*
X705000D03*
X710000D03*
X675500Y106000D03*
X680500D03*
X685500D03*
X710000Y546000D03*
X705000D03*
X700000D03*
X695000D03*
Y566000D03*
X700000D03*
X705000D03*
X710000D03*
X687000Y564000D03*
X682000D03*
X677000D03*
Y584000D03*
X682000D03*
X687000D03*
X710000Y999000D03*
X705000D03*
X700000D03*
X695000D03*
Y1019000D03*
X700000D03*
X705000D03*
X710000D03*
X677000Y1037000D03*
X682000D03*
X687000D03*
Y1017000D03*
X682000D03*
X677000D03*
X989120Y845050D03*
X984120D03*
X979120D03*
X974120D03*
Y865050D03*
X979120D03*
X984120D03*
X989120D03*
X1220600Y1326833D03*
X1225600D03*
X1230600D03*
X1235600D03*
Y1306733D03*
X1230600D03*
X1225600D03*
X1220600D03*
X1187394Y1326833D03*
X1192394D03*
X1197394D03*
X1202394D03*
Y1306733D03*
X1197394D03*
X1192394D03*
X1187394D03*
X1314500Y82000D03*
X1309500D03*
X1304500D03*
X1299500D03*
Y102000D03*
X1304500D03*
X1309500D03*
X1314500D03*
X1318000Y140000D03*
X1323000D03*
X1328000D03*
X1333000D03*
Y120000D03*
X1328000D03*
X1323000D03*
X1318000D03*
X1333500Y573000D03*
X1328500D03*
X1323500D03*
X1318500D03*
Y593000D03*
X1323500D03*
X1328500D03*
X1333500D03*
X1318500Y1045500D03*
X1323500D03*
X1328500D03*
X1333500D03*
Y1025500D03*
X1328500D03*
X1323500D03*
X1318500D03*
X1333100Y1430700D03*
X1338100D03*
Y1410700D03*
X1333100D03*
X1343100Y1430700D03*
X1348100D03*
Y1410700D03*
X1343100D03*
X1442500Y140000D03*
X1447500D03*
X1452500D03*
X1457500D03*
Y120000D03*
X1452500D03*
X1447500D03*
X1442500D03*
X1457500Y573000D03*
X1452500D03*
X1447500D03*
X1442500D03*
Y593000D03*
X1447500D03*
X1452500D03*
X1457500D03*
X1442500Y1045500D03*
X1447500D03*
X1452500D03*
X1457500D03*
Y1025500D03*
X1452500D03*
X1447500D03*
X1442500D03*
X1564000Y82000D03*
X1559000D03*
X1554000D03*
X1549000D03*
Y102000D03*
X1554000D03*
X1559000D03*
X1564000D03*
X1582000Y573000D03*
X1577000D03*
X1572000D03*
X1567000D03*
Y593000D03*
X1572000D03*
X1577000D03*
X1582000D03*
X1567000Y1045500D03*
X1572000D03*
X1577000D03*
X1582000D03*
Y1025500D03*
X1577000D03*
X1572000D03*
X1567000D03*
X1691000Y140000D03*
X1696000D03*
X1701000D03*
X1706000D03*
Y120000D03*
X1701000D03*
X1696000D03*
X1691000D03*
X1706000Y573000D03*
X1701000D03*
X1696000D03*
X1691000D03*
Y593000D03*
X1696000D03*
X1701000D03*
X1706000D03*
X1691000Y1045500D03*
X1696000D03*
X1701000D03*
X1706000D03*
Y1025500D03*
X1701000D03*
X1696000D03*
X1691000D03*
X1721326Y1430600D03*
Y1410600D03*
X1811300Y91100D03*
X1806300D03*
X1801300D03*
X1796300D03*
Y111100D03*
X1801300D03*
X1806300D03*
X1811300D03*
X1814500Y140000D03*
Y120000D03*
X1815000Y573000D03*
Y593000D03*
Y1045500D03*
Y1025500D03*
X1726326Y1430600D03*
X1731326D03*
X1736326D03*
Y1410600D03*
X1731326D03*
X1726326D03*
X1880500Y93000D03*
X1875500D03*
X1870500D03*
X1865500D03*
X1856000Y85500D03*
X1851000D03*
X1846000D03*
X1841000D03*
X1865500Y113000D03*
X1870500D03*
X1875500D03*
X1880500D03*
X1819500Y140000D03*
X1824500D03*
X1829500D03*
Y120000D03*
X1824500D03*
X1819500D03*
X1841000Y105500D03*
X1846000D03*
X1851000D03*
X1856000D03*
X1880500Y546000D03*
X1875500D03*
X1870500D03*
X1865500D03*
Y566000D03*
X1870500D03*
X1875500D03*
X1880500D03*
X1830000Y573000D03*
X1825000D03*
X1820000D03*
X1857500Y564000D03*
X1852500D03*
X1847500D03*
X1842500D03*
X1820000Y593000D03*
X1825000D03*
X1830000D03*
X1842500Y584000D03*
X1847500D03*
X1852500D03*
X1857500D03*
X1880500Y999000D03*
X1875500D03*
X1870500D03*
X1865500D03*
Y1019000D03*
X1870500D03*
X1875500D03*
X1880500D03*
X1820000Y1045500D03*
X1825000D03*
X1830000D03*
Y1025500D03*
X1825000D03*
X1820000D03*
X1842500Y1037000D03*
X1847500D03*
X1852500D03*
X1857500D03*
Y1017000D03*
X1852500D03*
X1847500D03*
X1842500D03*
G54D11*
X99823Y93819D03*
Y90669D03*
Y87520D03*
Y84370D03*
Y103268D03*
Y100118D03*
Y96969D03*
Y556024D03*
Y552874D03*
Y549725D03*
Y546575D03*
Y543425D03*
Y540276D03*
Y537126D03*
Y1008780D03*
Y1005630D03*
Y1002481D03*
Y999331D03*
Y996181D03*
Y993032D03*
Y989882D03*
X224035Y93819D03*
Y90669D03*
Y87520D03*
Y84370D03*
Y103268D03*
Y100118D03*
Y96969D03*
Y556024D03*
Y552874D03*
Y549725D03*
Y546575D03*
Y543425D03*
Y540276D03*
Y537126D03*
Y1008780D03*
Y1005630D03*
Y1002481D03*
Y999331D03*
Y996181D03*
Y993032D03*
Y989882D03*
X348248Y93819D03*
Y90669D03*
Y87520D03*
Y84370D03*
Y103268D03*
Y100118D03*
Y96969D03*
Y556024D03*
Y552874D03*
Y549725D03*
Y546575D03*
Y543425D03*
Y540276D03*
Y537126D03*
Y1008780D03*
Y1005630D03*
Y1002481D03*
Y999331D03*
Y996181D03*
Y993032D03*
Y989882D03*
X472460Y93819D03*
Y90669D03*
Y87520D03*
Y84370D03*
Y103268D03*
Y100118D03*
Y96969D03*
Y556024D03*
Y552874D03*
Y549725D03*
Y546575D03*
Y543425D03*
Y540276D03*
Y537126D03*
Y1008780D03*
Y1005630D03*
Y1002481D03*
Y999331D03*
Y996181D03*
Y993032D03*
Y989882D03*
X596673Y93819D03*
Y90669D03*
Y87520D03*
Y84370D03*
Y103268D03*
Y100118D03*
Y96969D03*
Y556024D03*
Y552874D03*
Y549725D03*
Y546575D03*
Y543425D03*
Y540276D03*
Y537126D03*
Y1008780D03*
Y1005630D03*
Y1002481D03*
Y999331D03*
Y996181D03*
Y993032D03*
Y989882D03*
X720886Y93819D03*
Y90669D03*
Y87520D03*
Y84370D03*
Y103268D03*
Y100118D03*
Y96969D03*
Y556024D03*
Y552874D03*
Y549725D03*
Y546575D03*
Y543425D03*
Y540276D03*
Y537126D03*
Y1008780D03*
Y1005630D03*
Y1002481D03*
Y999331D03*
Y996181D03*
Y993032D03*
Y989882D03*
X1270492Y93819D03*
Y90669D03*
Y87520D03*
Y84370D03*
Y103268D03*
Y100118D03*
Y96969D03*
Y556024D03*
Y552874D03*
Y549725D03*
Y546575D03*
Y543425D03*
Y540276D03*
Y537126D03*
Y1008780D03*
Y1005630D03*
Y1002481D03*
Y999331D03*
Y996181D03*
Y993032D03*
Y989882D03*
X1394705Y93819D03*
Y90669D03*
Y87520D03*
Y84370D03*
Y103268D03*
Y100118D03*
Y96969D03*
Y556024D03*
Y552874D03*
Y549725D03*
Y546575D03*
Y543425D03*
Y540276D03*
Y537126D03*
Y1008780D03*
Y1005630D03*
Y1002481D03*
Y999331D03*
Y996181D03*
Y993032D03*
Y989882D03*
X1518917Y93819D03*
Y90669D03*
Y87520D03*
Y84370D03*
Y103268D03*
Y100118D03*
Y96969D03*
Y556024D03*
Y552874D03*
Y549725D03*
Y546575D03*
Y543425D03*
Y540276D03*
Y537126D03*
Y1008780D03*
Y1005630D03*
Y1002481D03*
Y999331D03*
Y996181D03*
Y993032D03*
Y989882D03*
X1643130Y93819D03*
Y90669D03*
Y87520D03*
Y84370D03*
Y103268D03*
Y100118D03*
Y96969D03*
Y556024D03*
Y552874D03*
Y549725D03*
Y546575D03*
Y543425D03*
Y540276D03*
Y537126D03*
Y1008780D03*
Y1005630D03*
Y1002481D03*
Y999331D03*
Y996181D03*
Y993032D03*
Y989882D03*
X1767342Y93819D03*
Y90669D03*
Y87520D03*
Y84370D03*
Y103268D03*
Y100118D03*
Y96969D03*
Y556024D03*
Y552874D03*
Y549725D03*
Y546575D03*
Y543425D03*
Y540276D03*
Y537126D03*
Y1008780D03*
Y1005630D03*
Y1002481D03*
Y999331D03*
Y996181D03*
Y993032D03*
Y989882D03*
X1891555Y93819D03*
Y90669D03*
Y87520D03*
Y84370D03*
Y103268D03*
Y100118D03*
Y96969D03*
Y556024D03*
Y552874D03*
Y549725D03*
Y546575D03*
Y543425D03*
Y540276D03*
Y537126D03*
Y1008780D03*
Y1005630D03*
Y1002481D03*
Y999331D03*
Y996181D03*
Y993032D03*
Y989882D03*
G54D30*
X95500Y181800D03*
Y634300D03*
Y1087300D03*
X140500Y131900D03*
X219500Y181800D03*
X265000Y132000D03*
X219500Y634300D03*
X220000Y1087300D03*
X344000Y181800D03*
Y634300D03*
Y1087300D03*
X468000Y181800D03*
X389000Y132200D03*
X468000Y634300D03*
Y1087300D03*
X513600Y132100D03*
X528334Y1433529D03*
X528200Y1462400D03*
X592500Y181800D03*
X637300Y132100D03*
X592500Y634300D03*
Y1087300D03*
X651295Y1430719D03*
X716500Y181800D03*
X748400Y142900D03*
X716500Y634300D03*
X752500Y593800D03*
X716500Y1087300D03*
X752500Y1054300D03*
X838470Y942230D03*
X958738Y1418618D03*
X1131215Y1315870D03*
X1213033Y1313744D03*
X1180009Y1313953D03*
X1298500Y151800D03*
Y181300D03*
X1253000Y132200D03*
X1298500Y604800D03*
Y634300D03*
X1252800Y584900D03*
Y1037500D03*
X1298500Y1057300D03*
Y1086800D03*
X1422500Y151800D03*
Y181300D03*
X1376700Y132200D03*
X1422500Y604800D03*
Y634300D03*
Y1057300D03*
Y1086800D03*
X1501300Y132200D03*
X1547000Y151800D03*
Y181300D03*
X1625300Y132200D03*
X1547000Y604800D03*
Y634300D03*
Y1057300D03*
Y1086800D03*
X1671000Y151800D03*
Y181300D03*
Y604800D03*
Y634300D03*
Y1057300D03*
Y1086800D03*
X1795000Y151800D03*
Y181300D03*
X1749700Y131700D03*
X1795000Y604800D03*
Y634300D03*
Y1057300D03*
Y1086800D03*
X1887000Y181300D03*
Y634300D03*
Y1087300D03*
G54D12*
X67700Y91000D03*
X92200Y77000D03*
X60200Y65500D03*
X67700Y543500D03*
X92200Y529500D03*
X60200Y518000D03*
X89595Y905367D03*
X60200Y971000D03*
X92200Y982500D03*
X67700Y996500D03*
X187422Y467631D03*
X191700Y543500D03*
X184200Y518000D03*
X177008Y835918D03*
X184700Y971000D03*
X192200Y996500D03*
X188324Y1408800D03*
X117674Y1480400D03*
X129074Y1484200D03*
X218300Y57400D03*
X216200Y529500D03*
X216700Y982500D03*
X316200Y91000D03*
X340700Y77000D03*
X308700Y65500D03*
X316200Y543500D03*
X340700Y529500D03*
X308700Y518000D03*
Y971000D03*
X340700Y982500D03*
X316200Y996500D03*
X467200Y57500D03*
X440200Y543500D03*
X464700Y529500D03*
X432700Y518000D03*
Y971000D03*
X464700Y982500D03*
X440200Y996500D03*
X564700Y91000D03*
X557200Y65500D03*
X564700Y543500D03*
X557200Y518000D03*
Y971000D03*
X564700Y996500D03*
X510700Y1470500D03*
X528400Y1452100D03*
X528200Y1467000D03*
X589200Y77000D03*
Y529500D03*
Y982500D03*
X646895Y1425719D03*
X646995Y1441419D03*
X636200Y1464500D03*
X662000Y1468000D03*
X665200Y1444000D03*
X662000Y1464000D03*
Y1453500D03*
Y1457500D03*
X715700Y57400D03*
X688700Y543500D03*
X713200Y529500D03*
X681200Y518000D03*
Y971000D03*
X713200Y982500D03*
X688700Y996500D03*
X727200Y1453500D03*
X713700Y1443500D03*
X719700Y1458500D03*
Y1463000D03*
X684700Y1430000D03*
X692700D03*
X716700Y1438500D03*
X715800Y1475800D03*
X688200Y1476000D03*
X741432Y1466234D03*
X752932Y1465934D03*
X824690Y655190D03*
X818000Y772000D03*
Y781000D03*
X826200Y815000D03*
X827700Y893000D03*
X827587Y884453D03*
X946073Y556600D03*
X945788Y529107D03*
X946029Y551379D03*
X942927Y524023D03*
X874690Y647190D03*
Y655190D03*
X870500Y761000D03*
Y770000D03*
Y765500D03*
X878353Y807000D03*
X876200Y815000D03*
X912200Y782800D03*
X875700Y883000D03*
Y878500D03*
Y874000D03*
X933700Y875500D03*
X954438Y1412818D03*
Y1429318D03*
X963820Y770010D03*
Y774510D03*
X1029721Y830913D03*
X1004007Y903075D03*
X993597Y903465D03*
X1011481Y899075D03*
X1021739Y896965D03*
X1011200Y1117500D03*
X979200Y1201000D03*
Y1197000D03*
Y1209000D03*
Y1217000D03*
X1000143Y1417899D03*
X992143D03*
X1024143Y1426399D03*
X1021143Y1431399D03*
X1027143Y1451399D03*
Y1455899D03*
X1023950Y1496814D03*
X1045250Y1496914D03*
X972643Y1431899D03*
X968543Y1445399D03*
Y1441399D03*
X1057700Y824250D03*
Y814500D03*
Y837800D03*
Y828400D03*
X1078800Y1309495D03*
Y1304495D03*
Y1299375D03*
Y1292460D03*
X1105800Y1371200D03*
X1105812Y1391273D03*
X1105800Y1375200D03*
X1105812Y1383273D03*
X1196994Y918091D03*
X1196924Y912331D03*
X1210712Y1401814D03*
X1305000Y68900D03*
X1306800Y530000D03*
X1332700Y533500D03*
X1307800Y982200D03*
X1332700Y986000D03*
X1327350Y1408400D03*
X1263374Y1484900D03*
X1288074Y1480000D03*
X1274774Y1488600D03*
X1431300Y529900D03*
Y982400D03*
X1456700Y80500D03*
Y533500D03*
Y986000D03*
X1555400Y69300D03*
Y529800D03*
X1581200Y533500D03*
X1555700Y982600D03*
X1581200Y986000D03*
X1679600Y77000D03*
X1705200Y80500D03*
X1680000Y530100D03*
X1705200Y533500D03*
X1679600Y982300D03*
X1705200Y986000D03*
X1715576Y1408700D03*
X1656200Y1465000D03*
X1801100Y63200D03*
X1730191Y471049D03*
X1804000Y530100D03*
X1763200Y583500D03*
X1804595Y905367D03*
X1803700Y982200D03*
X1862500Y22300D03*
X1825600Y100800D03*
X1829200Y533500D03*
X1859200Y543500D03*
X1843200Y533500D03*
X1829200Y986000D03*
X1859200Y996500D03*
X1843200Y986500D03*
X1821226Y1470900D03*
G54D21*
X66500Y65000D03*
Y74000D03*
Y517500D03*
Y526500D03*
Y970500D03*
Y979500D03*
X190500Y517500D03*
Y526500D03*
X191000Y970500D03*
Y979500D03*
X174374Y1410900D03*
Y1401900D03*
X315000Y65000D03*
Y74000D03*
Y517500D03*
Y526500D03*
Y970500D03*
Y979500D03*
X439000Y517500D03*
Y526500D03*
Y970500D03*
Y979500D03*
X563500Y65000D03*
Y74000D03*
Y517500D03*
Y526500D03*
Y970500D03*
Y979500D03*
X687500Y517500D03*
Y526500D03*
Y970500D03*
Y979500D03*
X1317900Y59900D03*
Y68900D03*
X1313500Y1410900D03*
Y1401900D03*
X1570000Y60000D03*
Y69000D03*
X1701626Y1410900D03*
Y1401900D03*
X1868800Y22300D03*
Y31300D03*
X1849500Y533000D03*
Y542000D03*
Y986000D03*
Y995000D03*
G54D13*
X64300Y91000D03*
X88800Y77000D03*
X56800Y65500D03*
X64300Y543500D03*
X88800Y529500D03*
X56800Y518000D03*
X86195Y905367D03*
X56800Y971000D03*
X88800Y982500D03*
X64300Y996500D03*
X184022Y467631D03*
X188300Y543500D03*
X180800Y518000D03*
X173608Y835918D03*
X181300Y971000D03*
X188800Y996500D03*
X184924Y1408800D03*
X114274Y1480400D03*
X125674Y1484200D03*
X214900Y57400D03*
X212800Y529500D03*
X213300Y982500D03*
X312800Y91000D03*
X337300Y77000D03*
X305300Y65500D03*
X312800Y543500D03*
X337300Y529500D03*
X305300Y518000D03*
Y971000D03*
X337300Y982500D03*
X312800Y996500D03*
X463800Y57500D03*
X436800Y543500D03*
X461300Y529500D03*
X429300Y518000D03*
Y971000D03*
X461300Y982500D03*
X436800Y996500D03*
X561300Y91000D03*
X553800Y65500D03*
X561300Y543500D03*
X553800Y518000D03*
Y971000D03*
X561300Y996500D03*
X507300Y1470500D03*
X525000Y1452100D03*
X524800Y1467000D03*
X585800Y77000D03*
Y529500D03*
Y982500D03*
X643495Y1425719D03*
X643595Y1441419D03*
X632800Y1464500D03*
X658600Y1468000D03*
X661800Y1444000D03*
X658600Y1464000D03*
Y1453500D03*
Y1457500D03*
X712300Y57400D03*
X685300Y543500D03*
X709800Y529500D03*
X677800Y518000D03*
Y971000D03*
X709800Y982500D03*
X685300Y996500D03*
X723800Y1453500D03*
X710300Y1443500D03*
X716300Y1458500D03*
Y1463000D03*
X681300Y1430000D03*
X689300D03*
X713300Y1438500D03*
X712400Y1475800D03*
X684800Y1476000D03*
X738032Y1466234D03*
X749532Y1465934D03*
X821290Y655190D03*
X814600Y772000D03*
Y781000D03*
X822800Y815000D03*
X824300Y893000D03*
X824187Y884453D03*
X942673Y556600D03*
X942388Y529107D03*
X942629Y551379D03*
X939527Y524023D03*
X871290Y647190D03*
Y655190D03*
X867100Y761000D03*
Y770000D03*
Y765500D03*
X874953Y807000D03*
X872800Y815000D03*
X908800Y782800D03*
X872300Y883000D03*
Y878500D03*
Y874000D03*
X930300Y875500D03*
X951038Y1412818D03*
Y1429318D03*
X960420Y770010D03*
Y774510D03*
X1054300Y824250D03*
Y814500D03*
Y837800D03*
Y828400D03*
X1026321Y830913D03*
X1000607Y903075D03*
X990197Y903465D03*
X1008081Y899075D03*
X1018339Y896965D03*
X1007800Y1117500D03*
X975800Y1201000D03*
Y1197000D03*
Y1209000D03*
Y1217000D03*
X996743Y1417899D03*
X988743D03*
X1020743Y1426399D03*
X1017743Y1431399D03*
X1023743Y1451399D03*
Y1455899D03*
X1020550Y1496814D03*
X1041850Y1496914D03*
X969243Y1431899D03*
X965143Y1445399D03*
Y1441399D03*
X1075400Y1309495D03*
Y1304495D03*
Y1299375D03*
Y1292460D03*
X1102400Y1371200D03*
X1102412Y1391273D03*
X1102400Y1375200D03*
X1102412Y1383273D03*
X1193594Y918091D03*
X1193524Y912331D03*
X1207312Y1401814D03*
X1301600Y68900D03*
X1303400Y530000D03*
X1329300Y533500D03*
X1304400Y982200D03*
X1329300Y986000D03*
X1323950Y1408400D03*
X1259974Y1484900D03*
X1284674Y1480000D03*
X1271374Y1488600D03*
X1427900Y529900D03*
Y982400D03*
X1453300Y80500D03*
Y533500D03*
Y986000D03*
X1552000Y69300D03*
Y529800D03*
X1577800Y533500D03*
X1552300Y982600D03*
X1577800Y986000D03*
X1676200Y77000D03*
X1701800Y80500D03*
X1676600Y530100D03*
X1701800Y533500D03*
X1676200Y982300D03*
X1701800Y986000D03*
X1712176Y1408700D03*
X1652800Y1465000D03*
X1797700Y63200D03*
X1726791Y471049D03*
X1800600Y530100D03*
X1759800Y583500D03*
X1801195Y905367D03*
X1800300Y982200D03*
X1859100Y22300D03*
X1822200Y100800D03*
X1825800Y533500D03*
X1855800Y543500D03*
X1839800Y533500D03*
X1825800Y986000D03*
X1855800Y996500D03*
X1839800Y986500D03*
X1817826Y1470900D03*
G54D22*
X83060Y80700D03*
X80500D03*
X77940D03*
Y73300D03*
X80500D03*
X83060D03*
Y533200D03*
X80500D03*
X77940D03*
Y525800D03*
X80500D03*
X83060D03*
Y986200D03*
X80500D03*
X77940D03*
Y978800D03*
X80500D03*
X83060D03*
X207060Y533200D03*
X204500D03*
X201940D03*
Y525800D03*
X204500D03*
X207060D03*
X207560Y986200D03*
X205000D03*
X202440D03*
Y978800D03*
X205000D03*
X207560D03*
X331560Y80700D03*
X329000D03*
X326440D03*
Y73300D03*
X329000D03*
X331560D03*
Y533200D03*
X329000D03*
X326440D03*
Y525800D03*
X329000D03*
X331560D03*
Y986200D03*
X329000D03*
X326440D03*
Y978800D03*
X329000D03*
X331560D03*
X455560Y533200D03*
X453000D03*
X450440D03*
Y525800D03*
X453000D03*
X455560D03*
Y986200D03*
X453000D03*
X450440D03*
Y978800D03*
X453000D03*
X455560D03*
X574940Y80700D03*
Y73300D03*
Y533200D03*
Y525800D03*
Y986200D03*
Y978800D03*
X580060Y80700D03*
X577500D03*
Y73300D03*
X580060D03*
Y533200D03*
X577500D03*
Y525800D03*
X580060D03*
Y986200D03*
X577500D03*
Y978800D03*
X580060D03*
X704060Y533200D03*
X701500D03*
X698940D03*
Y525800D03*
X701500D03*
X704060D03*
Y986200D03*
X701500D03*
X698940D03*
Y978800D03*
X701500D03*
X704060D03*
X1801796Y1484390D03*
X1799236D03*
X1796676D03*
Y1476990D03*
X1799236D03*
X1801796D03*
X1886060Y36700D03*
X1883500D03*
X1880940D03*
Y29300D03*
X1883500D03*
X1886060D03*
G54D40*
X51209Y393253D03*
X58709Y389378D03*
Y397128D03*
X38942Y845907D03*
X46442Y842032D03*
Y849782D03*
X185342Y392907D03*
X192842Y389032D03*
Y396782D03*
X160342Y840907D03*
X167842Y837032D03*
Y844782D03*
X287042Y393207D03*
Y845907D03*
X294542Y389332D03*
Y397082D03*
Y842032D03*
Y849782D03*
X411542Y392907D03*
X419042Y389032D03*
Y396782D03*
X411242Y845607D03*
X418742Y841732D03*
Y849482D03*
X535742Y393207D03*
X543242Y389332D03*
Y397082D03*
X575148Y846130D03*
X646742Y392907D03*
X654242Y389032D03*
Y396782D03*
X652142Y845607D03*
X659642Y841732D03*
Y849482D03*
X582648Y842255D03*
Y850005D03*
X1209611Y845907D03*
X1217111Y842032D03*
Y849782D03*
X1255445Y392994D03*
X1262945Y389119D03*
Y396869D03*
X1333824Y393151D03*
X1341324Y389276D03*
Y397026D03*
X1333824Y845907D03*
X1341324Y842032D03*
Y849782D03*
X1458036Y393151D03*
X1465536Y389276D03*
Y397026D03*
X1458036Y845907D03*
X1465536Y842032D03*
Y849782D03*
X1582249Y393151D03*
X1589749Y389276D03*
Y397026D03*
X1582249Y845907D03*
X1589749Y842032D03*
Y849782D03*
X1706461Y845907D03*
X1713961Y842032D03*
Y849782D03*
X1797642Y393507D03*
X1805142Y389632D03*
Y397382D03*
X1830674Y845907D03*
X1838174Y842032D03*
Y849782D03*
G54D31*
X95500Y176200D03*
Y628700D03*
Y1081700D03*
X140500Y126300D03*
X219500Y176200D03*
X265000Y126400D03*
X219500Y628700D03*
X220000Y1081700D03*
X344000Y176200D03*
Y628700D03*
Y1081700D03*
X468000Y176200D03*
X389000Y126600D03*
X468000Y628700D03*
Y1081700D03*
X513600Y126500D03*
X528334Y1427929D03*
X528200Y1456800D03*
X592500Y176200D03*
X637300Y126500D03*
X592500Y628700D03*
Y1081700D03*
X651295Y1425119D03*
X716500Y176200D03*
X748400Y137300D03*
X716500Y628700D03*
X752500Y588200D03*
Y1048700D03*
X716500Y1081700D03*
X838470Y936630D03*
X958738Y1413018D03*
X1131215Y1310270D03*
X1213033Y1308144D03*
X1180009Y1308353D03*
X1298500Y146200D03*
Y175700D03*
X1253000Y126600D03*
X1298500Y599200D03*
Y628700D03*
X1252800Y579300D03*
Y1031900D03*
X1298500Y1051700D03*
Y1081200D03*
X1422500Y146200D03*
Y175700D03*
X1376700Y126600D03*
X1422500Y599200D03*
Y628700D03*
Y1051700D03*
Y1081200D03*
X1501300Y126600D03*
X1547000Y146200D03*
Y175700D03*
X1625300Y126600D03*
X1547000Y599200D03*
Y628700D03*
Y1051700D03*
Y1081200D03*
X1671000Y146200D03*
Y175700D03*
Y599200D03*
Y628700D03*
Y1051700D03*
Y1081200D03*
X1795000Y146200D03*
Y175700D03*
X1749700Y126100D03*
X1795000Y599200D03*
Y628700D03*
Y1051700D03*
Y1081200D03*
X1887000Y175700D03*
Y628700D03*
Y1081700D03*
G54D50*
X184874Y1416450D03*
X107474Y1458600D03*
X198800Y37400D03*
X440400Y35700D03*
X524211Y1429134D03*
X669761Y1453700D03*
X695600Y37300D03*
X834470Y937130D03*
X924000Y881700D03*
X951569Y1399632D03*
X950339Y1387003D03*
X1002118Y1464065D03*
X978443Y1441599D03*
X1125615Y1311270D03*
X1175800Y1309100D03*
X1208933Y1309144D03*
X1200962Y1405802D03*
X1324000Y1416450D03*
X1712126D03*
X1803100Y75000D03*
G54D41*
X118209Y81319D03*
Y76319D03*
Y71319D03*
Y66319D03*
Y61319D03*
Y56319D03*
Y51319D03*
Y176319D03*
Y171319D03*
Y166319D03*
Y161319D03*
Y156319D03*
Y151319D03*
Y146319D03*
Y141319D03*
Y136319D03*
Y131319D03*
Y126319D03*
Y121319D03*
Y116319D03*
Y111319D03*
Y106319D03*
Y569075D03*
Y564075D03*
Y559075D03*
Y534075D03*
Y529075D03*
Y524075D03*
Y519075D03*
Y514075D03*
Y509075D03*
Y504075D03*
Y629075D03*
Y624075D03*
Y619075D03*
Y614075D03*
Y609075D03*
Y604075D03*
Y599075D03*
Y594075D03*
Y589075D03*
Y584075D03*
Y579075D03*
Y574075D03*
Y1046831D03*
Y1041831D03*
Y1036831D03*
Y1031831D03*
Y1026831D03*
Y1021831D03*
Y1016831D03*
Y1011831D03*
Y986831D03*
Y981831D03*
Y976831D03*
Y971831D03*
Y966831D03*
Y961831D03*
Y956831D03*
Y1081831D03*
Y1076831D03*
Y1071831D03*
Y1066831D03*
Y1061831D03*
Y1056831D03*
Y1051831D03*
X242421Y81319D03*
Y76319D03*
Y71319D03*
Y66319D03*
Y61319D03*
Y56319D03*
Y51319D03*
Y176319D03*
Y171319D03*
Y166319D03*
Y161319D03*
Y156319D03*
Y151319D03*
Y146319D03*
Y141319D03*
Y136319D03*
Y131319D03*
Y126319D03*
Y121319D03*
Y116319D03*
Y111319D03*
Y106319D03*
Y569075D03*
Y564075D03*
Y559075D03*
Y534075D03*
Y529075D03*
Y524075D03*
Y519075D03*
Y514075D03*
Y509075D03*
Y504075D03*
Y629075D03*
Y624075D03*
Y619075D03*
Y614075D03*
Y609075D03*
Y604075D03*
Y599075D03*
Y594075D03*
Y589075D03*
Y584075D03*
Y579075D03*
Y574075D03*
Y1046831D03*
Y1041831D03*
Y1036831D03*
Y1031831D03*
Y1026831D03*
Y1021831D03*
Y1016831D03*
Y1011831D03*
Y986831D03*
Y981831D03*
Y976831D03*
Y971831D03*
Y966831D03*
Y961831D03*
Y956831D03*
Y1081831D03*
Y1076831D03*
Y1071831D03*
Y1066831D03*
Y1061831D03*
Y1056831D03*
Y1051831D03*
X366634Y81319D03*
Y76319D03*
Y71319D03*
Y66319D03*
Y61319D03*
Y56319D03*
Y51319D03*
Y176319D03*
Y171319D03*
Y166319D03*
Y161319D03*
Y156319D03*
Y151319D03*
Y146319D03*
Y141319D03*
Y136319D03*
Y131319D03*
Y126319D03*
Y121319D03*
Y116319D03*
Y111319D03*
Y106319D03*
Y569075D03*
Y564075D03*
Y559075D03*
Y534075D03*
Y529075D03*
Y524075D03*
Y519075D03*
Y514075D03*
Y509075D03*
Y504075D03*
Y629075D03*
Y624075D03*
Y619075D03*
Y614075D03*
Y609075D03*
Y604075D03*
Y599075D03*
Y594075D03*
Y589075D03*
Y584075D03*
Y579075D03*
Y574075D03*
Y1046831D03*
Y1041831D03*
Y1036831D03*
Y1031831D03*
Y1026831D03*
Y1021831D03*
Y1016831D03*
Y1011831D03*
Y986831D03*
Y981831D03*
Y976831D03*
Y971831D03*
Y966831D03*
Y961831D03*
Y956831D03*
Y1081831D03*
Y1076831D03*
Y1071831D03*
Y1066831D03*
Y1061831D03*
Y1056831D03*
Y1051831D03*
X490846Y81319D03*
Y76319D03*
Y71319D03*
Y66319D03*
Y61319D03*
Y56319D03*
Y51319D03*
Y176319D03*
Y171319D03*
Y166319D03*
Y161319D03*
Y156319D03*
Y151319D03*
Y146319D03*
Y141319D03*
Y136319D03*
Y131319D03*
Y126319D03*
Y121319D03*
Y116319D03*
Y111319D03*
Y106319D03*
Y569075D03*
Y564075D03*
Y559075D03*
Y534075D03*
Y529075D03*
Y524075D03*
Y519075D03*
Y514075D03*
Y509075D03*
Y504075D03*
Y629075D03*
Y624075D03*
Y619075D03*
Y614075D03*
Y609075D03*
Y604075D03*
Y599075D03*
Y594075D03*
Y589075D03*
Y584075D03*
Y579075D03*
Y574075D03*
Y1046831D03*
Y1041831D03*
Y1036831D03*
Y1031831D03*
Y1026831D03*
Y1021831D03*
Y1016831D03*
Y1011831D03*
Y986831D03*
Y981831D03*
Y976831D03*
Y971831D03*
Y966831D03*
Y961831D03*
Y956831D03*
Y1081831D03*
Y1076831D03*
Y1071831D03*
Y1066831D03*
Y1061831D03*
Y1056831D03*
Y1051831D03*
X615059Y81319D03*
Y76319D03*
Y71319D03*
Y66319D03*
Y61319D03*
Y56319D03*
Y51319D03*
Y176319D03*
Y171319D03*
Y166319D03*
Y161319D03*
Y156319D03*
Y151319D03*
Y146319D03*
Y141319D03*
Y136319D03*
Y131319D03*
Y126319D03*
Y121319D03*
Y116319D03*
Y111319D03*
Y106319D03*
Y569075D03*
Y564075D03*
Y559075D03*
Y534075D03*
Y529075D03*
Y524075D03*
Y519075D03*
Y514075D03*
Y509075D03*
Y504075D03*
Y629075D03*
Y624075D03*
Y619075D03*
Y614075D03*
Y609075D03*
Y604075D03*
Y599075D03*
Y594075D03*
Y589075D03*
Y584075D03*
Y579075D03*
Y574075D03*
Y1046831D03*
Y1041831D03*
Y1036831D03*
Y1031831D03*
Y1026831D03*
Y1021831D03*
Y1016831D03*
Y1011831D03*
Y986831D03*
Y981831D03*
Y976831D03*
Y971831D03*
Y966831D03*
Y961831D03*
Y956831D03*
Y1081831D03*
Y1076831D03*
Y1071831D03*
Y1066831D03*
Y1061831D03*
Y1056831D03*
Y1051831D03*
X739272Y81319D03*
Y76319D03*
Y71319D03*
Y66319D03*
Y61319D03*
Y56319D03*
Y51319D03*
Y176319D03*
Y171319D03*
Y166319D03*
Y161319D03*
Y156319D03*
Y151319D03*
Y146319D03*
Y141319D03*
Y136319D03*
Y131319D03*
Y126319D03*
Y121319D03*
Y116319D03*
Y111319D03*
Y106319D03*
Y569075D03*
Y564075D03*
Y559075D03*
Y534075D03*
Y529075D03*
Y524075D03*
Y519075D03*
Y514075D03*
Y509075D03*
Y504075D03*
Y629075D03*
Y624075D03*
Y619075D03*
Y614075D03*
Y609075D03*
Y604075D03*
Y599075D03*
Y594075D03*
Y589075D03*
Y584075D03*
Y579075D03*
Y574075D03*
Y1046831D03*
Y1041831D03*
Y1036831D03*
Y1031831D03*
Y1026831D03*
Y1021831D03*
Y1016831D03*
Y1011831D03*
Y986831D03*
Y981831D03*
Y976831D03*
Y971831D03*
Y966831D03*
Y961831D03*
Y956831D03*
Y1081831D03*
Y1076831D03*
Y1071831D03*
Y1066831D03*
Y1061831D03*
Y1056831D03*
Y1051831D03*
X1288878Y81319D03*
Y76319D03*
Y71319D03*
Y66319D03*
Y61319D03*
Y56319D03*
Y51319D03*
Y176319D03*
Y171319D03*
Y166319D03*
Y161319D03*
Y156319D03*
Y151319D03*
Y146319D03*
Y141319D03*
Y136319D03*
Y131319D03*
Y126319D03*
Y121319D03*
Y116319D03*
Y111319D03*
Y106319D03*
Y569075D03*
Y564075D03*
Y559075D03*
Y534075D03*
Y529075D03*
Y524075D03*
Y519075D03*
Y514075D03*
Y509075D03*
Y504075D03*
Y629075D03*
Y624075D03*
Y619075D03*
Y614075D03*
Y609075D03*
Y604075D03*
Y599075D03*
Y594075D03*
Y589075D03*
Y584075D03*
Y579075D03*
Y574075D03*
Y1046831D03*
Y1041831D03*
Y1036831D03*
Y1031831D03*
Y1026831D03*
Y1021831D03*
Y1016831D03*
Y1011831D03*
Y986831D03*
Y981831D03*
Y976831D03*
Y971831D03*
Y966831D03*
Y961831D03*
Y956831D03*
Y1081831D03*
Y1076831D03*
Y1071831D03*
Y1066831D03*
Y1061831D03*
Y1056831D03*
Y1051831D03*
X1413091Y81319D03*
Y76319D03*
Y71319D03*
Y66319D03*
Y61319D03*
Y56319D03*
Y51319D03*
Y176319D03*
Y171319D03*
Y166319D03*
Y161319D03*
Y156319D03*
Y151319D03*
Y146319D03*
Y141319D03*
Y136319D03*
Y131319D03*
Y126319D03*
Y121319D03*
Y116319D03*
Y111319D03*
Y106319D03*
Y569075D03*
Y564075D03*
Y559075D03*
Y534075D03*
Y529075D03*
Y524075D03*
Y519075D03*
Y514075D03*
Y509075D03*
Y504075D03*
Y629075D03*
Y624075D03*
Y619075D03*
Y614075D03*
Y609075D03*
Y604075D03*
Y599075D03*
Y594075D03*
Y589075D03*
Y584075D03*
Y579075D03*
Y574075D03*
Y1046831D03*
Y1041831D03*
Y1036831D03*
Y1031831D03*
Y1026831D03*
Y1021831D03*
Y1016831D03*
Y1011831D03*
Y986831D03*
Y981831D03*
Y976831D03*
Y971831D03*
Y966831D03*
Y961831D03*
Y956831D03*
Y1081831D03*
Y1076831D03*
Y1071831D03*
Y1066831D03*
Y1061831D03*
Y1056831D03*
Y1051831D03*
X1537303Y81319D03*
Y76319D03*
Y71319D03*
Y66319D03*
Y61319D03*
Y56319D03*
Y51319D03*
Y176319D03*
Y171319D03*
Y166319D03*
Y161319D03*
Y156319D03*
Y151319D03*
Y146319D03*
Y141319D03*
Y136319D03*
Y131319D03*
Y126319D03*
Y121319D03*
Y116319D03*
Y111319D03*
Y106319D03*
Y569075D03*
Y564075D03*
Y559075D03*
Y534075D03*
Y529075D03*
Y524075D03*
Y519075D03*
Y514075D03*
Y509075D03*
Y504075D03*
Y629075D03*
Y624075D03*
Y619075D03*
Y614075D03*
Y609075D03*
Y604075D03*
Y599075D03*
Y594075D03*
Y589075D03*
Y584075D03*
Y579075D03*
Y574075D03*
Y1046831D03*
Y1041831D03*
Y1036831D03*
Y1031831D03*
Y1026831D03*
Y1021831D03*
Y1016831D03*
Y1011831D03*
Y986831D03*
Y981831D03*
Y976831D03*
Y971831D03*
Y966831D03*
Y961831D03*
Y956831D03*
Y1081831D03*
Y1076831D03*
Y1071831D03*
Y1066831D03*
Y1061831D03*
Y1056831D03*
Y1051831D03*
X1661516Y81319D03*
Y76319D03*
Y71319D03*
Y66319D03*
Y61319D03*
Y56319D03*
Y51319D03*
Y176319D03*
Y171319D03*
Y166319D03*
Y161319D03*
Y156319D03*
Y151319D03*
Y146319D03*
Y141319D03*
Y136319D03*
Y131319D03*
Y126319D03*
Y121319D03*
Y116319D03*
Y111319D03*
Y106319D03*
Y569075D03*
Y564075D03*
Y559075D03*
Y534075D03*
Y529075D03*
Y524075D03*
Y519075D03*
Y514075D03*
Y509075D03*
Y504075D03*
Y629075D03*
Y624075D03*
Y619075D03*
Y614075D03*
Y609075D03*
Y604075D03*
Y599075D03*
Y594075D03*
Y589075D03*
Y584075D03*
Y579075D03*
Y574075D03*
Y1046831D03*
Y1041831D03*
Y1036831D03*
Y1031831D03*
Y1026831D03*
Y1021831D03*
Y1016831D03*
Y1011831D03*
Y986831D03*
Y981831D03*
Y976831D03*
Y971831D03*
Y966831D03*
Y961831D03*
Y956831D03*
Y1081831D03*
Y1076831D03*
Y1071831D03*
Y1066831D03*
Y1061831D03*
Y1056831D03*
Y1051831D03*
X1785728Y81319D03*
Y76319D03*
Y71319D03*
Y66319D03*
Y61319D03*
Y56319D03*
Y51319D03*
Y176319D03*
Y171319D03*
Y166319D03*
Y161319D03*
Y156319D03*
Y151319D03*
Y146319D03*
Y141319D03*
Y136319D03*
Y131319D03*
Y126319D03*
Y121319D03*
Y116319D03*
Y111319D03*
Y106319D03*
Y569075D03*
Y564075D03*
Y559075D03*
Y534075D03*
Y529075D03*
Y524075D03*
Y519075D03*
Y514075D03*
Y509075D03*
Y504075D03*
Y629075D03*
Y624075D03*
Y619075D03*
Y614075D03*
Y609075D03*
Y604075D03*
Y599075D03*
Y594075D03*
Y589075D03*
Y584075D03*
Y579075D03*
Y574075D03*
Y1046831D03*
Y1041831D03*
Y1036831D03*
Y1031831D03*
Y1026831D03*
Y1021831D03*
Y1016831D03*
Y1011831D03*
Y986831D03*
Y981831D03*
Y976831D03*
Y971831D03*
Y966831D03*
Y961831D03*
Y956831D03*
Y1081831D03*
Y1076831D03*
Y1071831D03*
Y1066831D03*
Y1061831D03*
Y1056831D03*
Y1051831D03*
X1909941Y81319D03*
Y76319D03*
Y71319D03*
Y66319D03*
Y61319D03*
Y56319D03*
Y51319D03*
Y176319D03*
Y171319D03*
Y166319D03*
Y161319D03*
Y156319D03*
Y151319D03*
Y146319D03*
Y141319D03*
Y136319D03*
Y131319D03*
Y126319D03*
Y121319D03*
Y116319D03*
Y111319D03*
Y106319D03*
Y569075D03*
Y564075D03*
Y559075D03*
Y534075D03*
Y529075D03*
Y524075D03*
Y519075D03*
Y514075D03*
Y509075D03*
Y504075D03*
Y629075D03*
Y624075D03*
Y619075D03*
Y614075D03*
Y609075D03*
Y604075D03*
Y599075D03*
Y594075D03*
Y589075D03*
Y584075D03*
Y579075D03*
Y574075D03*
Y1046831D03*
Y1041831D03*
Y1036831D03*
Y1031831D03*
Y1026831D03*
Y1021831D03*
Y1016831D03*
Y1011831D03*
Y986831D03*
Y981831D03*
Y976831D03*
Y971831D03*
Y966831D03*
Y961831D03*
Y956831D03*
Y1081831D03*
Y1076831D03*
Y1071831D03*
Y1066831D03*
Y1061831D03*
Y1056831D03*
Y1051831D03*
G54D32*
X73500Y126000D03*
X84500D03*
X69000Y140500D03*
X80000D03*
X73500Y578500D03*
X84500D03*
X69000Y593000D03*
X80000D03*
X73500Y1031500D03*
X84500D03*
X69000Y1046000D03*
X80000D03*
X193000Y140500D03*
Y593000D03*
X193500Y1046000D03*
X197500Y126000D03*
X208500D03*
X204000Y140500D03*
X197500Y578500D03*
X208500D03*
X204000Y593000D03*
X198000Y1031500D03*
X209000D03*
X204500Y1046000D03*
X322000Y126000D03*
X333000D03*
X317500Y140500D03*
X328500D03*
X322000Y578500D03*
X333000D03*
X317500Y593000D03*
X328500D03*
X322000Y1031500D03*
X333000D03*
X317500Y1046000D03*
X328500D03*
X446000Y126000D03*
X457000D03*
X441500Y140500D03*
X452500D03*
X446000Y578500D03*
X457000D03*
X441500Y593000D03*
X452500D03*
X446000Y1031500D03*
X457000D03*
X441500Y1046000D03*
X452500D03*
X570500Y126000D03*
X566000Y140500D03*
X577000D03*
X570500Y578500D03*
X566000Y593000D03*
X577000D03*
X570500Y1031500D03*
X566000Y1046000D03*
X577000D03*
X581500Y126000D03*
Y578500D03*
Y1031500D03*
X694500Y126000D03*
X705500D03*
X690000Y140500D03*
X701000D03*
X694500Y578500D03*
X705500D03*
X690000Y593000D03*
X701000D03*
X694500Y1031500D03*
X705500D03*
X690000Y1046000D03*
X701000D03*
X1310500Y126000D03*
X1299500D03*
X1319000Y159800D03*
X1308000D03*
X1310500Y579000D03*
X1299500D03*
X1318700Y612600D03*
X1307700D03*
X1310500Y1031500D03*
X1299500D03*
X1319000Y1065300D03*
X1308000D03*
X1434500Y126000D03*
X1423500D03*
X1431600Y159800D03*
X1434500Y579000D03*
X1423500D03*
X1432000Y612600D03*
X1434500Y1031500D03*
X1423500D03*
X1432000Y1065300D03*
X1442600Y159800D03*
X1443000Y612600D03*
Y1065300D03*
X1559000Y126000D03*
X1548000D03*
X1567400Y159800D03*
X1556400D03*
X1559000Y579000D03*
X1548000D03*
X1567300Y612600D03*
X1556300D03*
X1559000Y1031500D03*
X1548000D03*
X1567600Y1065500D03*
X1556600D03*
X1683000Y126000D03*
X1672000D03*
X1690400Y160000D03*
X1679400D03*
X1683000Y579000D03*
X1672000D03*
X1691600Y612500D03*
X1680600D03*
X1683000Y1031500D03*
X1672000D03*
X1691400Y1065300D03*
X1680400D03*
X1807000Y126000D03*
X1796000D03*
X1815500Y159700D03*
X1804500D03*
X1807000Y579000D03*
X1796000D03*
X1815800Y612500D03*
X1804800D03*
X1807000Y1031500D03*
X1796000D03*
X1815700Y1065300D03*
X1804700D03*
X1865000Y125500D03*
X1876000D03*
X1860500Y140000D03*
X1871500D03*
X1865000Y578500D03*
X1876000D03*
X1860500Y593000D03*
X1871500D03*
X1865000Y1031500D03*
X1876000D03*
X1860500Y1046000D03*
X1871500D03*
G54D14*
X88800Y72400D03*
X85600Y62800D03*
X56800Y96500D03*
X55259Y383528D03*
X69992Y403305D03*
X88600Y525300D03*
X86900Y516800D03*
X56800Y549000D03*
X42992Y836182D03*
X57725Y855959D03*
X94563Y908025D03*
X93655Y899023D03*
X86197Y901301D03*
X71363Y909325D03*
X70063Y892025D03*
X56800Y1002000D03*
X88800Y968000D03*
Y972500D03*
X195300Y78500D03*
X160800Y25100D03*
X157100Y32100D03*
X172200Y25100D03*
X160800Y21100D03*
X172200Y20900D03*
X168400Y29200D03*
X144100Y44400D03*
Y48500D03*
X192390Y470289D03*
X191482Y461287D03*
X184024Y463565D03*
X169190Y471589D03*
X167890Y454289D03*
X189392Y383182D03*
X180800Y549000D03*
X137300Y583000D03*
X180725Y855659D03*
X106363Y911925D03*
X106322Y903550D03*
X137300Y1036000D03*
X181300Y1002000D03*
X137774Y1472900D03*
X138674Y1452500D03*
Y1434000D03*
X124874Y1479100D03*
X203800Y45100D03*
X204190Y474189D03*
X204149Y465814D03*
X204125Y402959D03*
X212700Y525200D03*
X211200Y516600D03*
X261300Y583000D03*
X210900Y969700D03*
X213300Y978100D03*
X261000Y1036000D03*
X337200Y72600D03*
X335000Y63700D03*
X305300Y96500D03*
X291092Y383482D03*
X305825Y403259D03*
X337300Y525300D03*
X335100Y516800D03*
X305300Y549000D03*
X385800Y583000D03*
X291092Y836182D03*
X305825Y855959D03*
X305300Y1002000D03*
X334800Y969400D03*
X337200Y978200D03*
X385800Y1036000D03*
X452000Y44500D03*
X415592Y383182D03*
X430325Y402959D03*
X461300Y525300D03*
X459400Y516900D03*
X429300Y549000D03*
X415292Y835876D03*
X430025Y855659D03*
X429300Y1002000D03*
X459200Y969200D03*
X461200Y978000D03*
X553800Y96500D03*
X539792Y383482D03*
X554525Y403259D03*
X553800Y549000D03*
X509800Y583000D03*
Y1036000D03*
X553800Y1002000D03*
X585700Y72800D03*
X583800Y64300D03*
X650792Y383182D03*
X665525Y402959D03*
X585700Y525400D03*
X634300Y583000D03*
X656192Y835882D03*
X670925Y855659D03*
X579198Y836405D03*
X594105Y856859D03*
X583100Y969500D03*
X585800Y978100D03*
X634300Y1036000D03*
X668300Y1430000D03*
X692300Y78500D03*
X701300Y45050D03*
X748300Y130500D03*
X709700Y525300D03*
X677800Y549000D03*
Y1002000D03*
X707500Y969600D03*
X709900Y978300D03*
X749700Y1036000D03*
X710800Y1453500D03*
X712100Y1467300D03*
X723800Y1449000D03*
X712200Y1471600D03*
X821290Y659190D03*
Y647190D03*
Y651190D03*
X814600Y776500D03*
X814500Y785500D03*
X814600Y767500D03*
X822800Y819000D03*
Y807000D03*
Y811000D03*
X824300Y897500D03*
Y888500D03*
X824187Y880256D03*
X871290Y643190D03*
Y651190D03*
X867100Y756500D03*
X874953Y811000D03*
X872800Y803000D03*
X916100Y764800D03*
X908800Y774000D03*
Y778000D03*
X872300Y869500D03*
X954800Y898500D03*
X940800D03*
X955350Y1403400D03*
Y1399400D03*
X989548Y539555D03*
X991738Y517437D03*
X996141Y552081D03*
X991763Y526457D03*
X960420Y761010D03*
Y779010D03*
Y765510D03*
X1034181Y855984D03*
X1020300Y842500D03*
X1034184Y851705D03*
X1026462Y849214D03*
X1029642Y825127D03*
X1000607Y899075D03*
X990197Y895065D03*
X1008081Y903075D03*
X1018339Y900965D03*
X1024074Y939306D03*
X975800Y1225000D03*
Y1205000D03*
Y1221000D03*
Y1213000D03*
X975743Y1418699D03*
X1034150Y1496914D03*
X1020550Y1492814D03*
X1041850D03*
X1034150D03*
X1126800Y1291700D03*
Y1296700D03*
X1102412Y1379273D03*
Y1399273D03*
Y1395273D03*
Y1387273D03*
X1111800Y1358500D03*
X1213661Y836182D03*
X1228394Y855959D03*
X1184800Y892600D03*
Y886000D03*
Y906100D03*
Y899500D03*
X1330800Y109500D03*
X1337874Y383426D03*
X1259495Y383269D03*
X1274228Y403046D03*
X1331800Y562500D03*
X1337874Y836182D03*
X1331800Y1015000D03*
X1284674Y1471500D03*
X1285674Y1452500D03*
Y1434000D03*
X1271389Y1483400D03*
X1432300Y77000D03*
X1352607Y403203D03*
Y855959D03*
X1455800Y109500D03*
X1462086Y383426D03*
X1476819Y403203D03*
X1455800Y562500D03*
X1462086Y836182D03*
X1476819Y855959D03*
X1455800Y1015000D03*
X1601200Y129000D03*
X1586299Y383426D03*
X1601032Y403203D03*
X1580300Y562500D03*
X1586299Y836182D03*
X1601032Y855959D03*
X1580300Y1015000D03*
X1704300Y109500D03*
X1711959Y475007D03*
X1710659Y457707D03*
X1704300Y562500D03*
X1710511Y836182D03*
X1704300Y1015000D03*
X1665926Y1452500D03*
Y1434000D03*
X1812800Y64400D03*
X1735159Y473707D03*
X1746918Y469232D03*
X1734251Y464705D03*
X1726793Y466983D03*
X1801692Y383782D03*
X1816425Y403559D03*
X1749992Y402630D03*
X1764201Y402301D03*
X1746959Y477607D03*
X1725244Y855959D03*
X1809563Y908025D03*
X1808655Y899023D03*
X1801197Y901301D03*
X1786363Y909325D03*
X1785063Y892025D03*
X1803441Y1490100D03*
X1806411Y1471000D03*
X1818978Y85039D03*
Y80939D03*
X1878300Y77500D03*
X1862800Y78000D03*
X1864000Y38100D03*
X1821900Y32000D03*
X1827500Y25100D03*
Y20900D03*
X1835000Y29300D03*
X1838900Y25200D03*
Y21100D03*
X1827300Y109500D03*
X1828300Y562500D03*
X1876200Y530600D03*
X1848300Y549000D03*
X1849800Y527000D03*
X1834724Y836182D03*
X1849457Y855959D03*
X1821363Y911925D03*
X1821322Y903550D03*
X1828300Y1015000D03*
X1848300Y1002000D03*
X1849800Y980000D03*
G54D23*
X77300Y67250D03*
X60000Y80000D03*
X67750Y84500D03*
X77100Y62800D03*
X85600Y67700D03*
X83000Y147500D03*
X69000Y148000D03*
X86700Y133000D03*
X58709Y376696D03*
X72049Y349667D03*
X72600Y365900D03*
X53713Y367631D03*
X69567Y380781D03*
X77300Y519750D03*
X60000Y532500D03*
X68100Y537000D03*
X77200Y515100D03*
X86850Y520600D03*
X83000Y600000D03*
X69000Y600500D03*
X86500Y585400D03*
X57300Y751562D03*
X46442Y829350D03*
X72049Y808105D03*
X68109Y785607D03*
X44000Y819500D03*
X79563Y910125D03*
X97263Y913025D03*
X86263D03*
X77263Y894425D03*
X71313Y904525D03*
X65763Y875525D03*
X86500Y1038500D03*
X77300Y972750D03*
X60000Y985500D03*
X69000Y989000D03*
X63000Y964500D03*
X83000Y970000D03*
Y1053000D03*
X69000Y1053500D03*
X188841Y79022D03*
X195250Y73500D03*
X151160Y18699D03*
X168100Y25300D03*
X168200Y20500D03*
X140200Y48400D03*
X144400Y40500D03*
X136200Y126150D03*
X193000Y148000D03*
X192842Y376350D03*
X180300Y330300D03*
X184060Y300300D03*
X187450Y445273D03*
X177390Y472389D03*
X195090Y475289D03*
X184090D03*
X175090Y456689D03*
X169140Y466789D03*
X164418Y438162D03*
X184000Y532500D03*
X192499Y536649D03*
X137250Y588500D03*
X193000Y600500D03*
X169442Y829050D03*
X192321Y785355D03*
X165500Y822058D03*
X180300Y769500D03*
X129298Y888025D03*
X112763Y869025D03*
X102763Y873035D03*
X102863Y880125D03*
X184500Y985500D03*
X193949Y989097D03*
X137250Y1041500D03*
X193500Y1053500D03*
X168674Y1414200D03*
X137634Y1416776D03*
X184874Y1412600D03*
X116374Y1497100D03*
X109774Y1480300D03*
X124174Y1466600D03*
X104974Y1485200D03*
X124574Y1488200D03*
X119074Y1442100D03*
X113314Y1445840D03*
X105974Y1469500D03*
X124134Y1474900D03*
X211000Y57400D03*
X211162Y45100D03*
X211086Y73750D03*
X207000Y147500D03*
X260400Y126350D03*
X210960Y132800D03*
X218200Y360600D03*
X204300Y351300D03*
X227434Y450289D03*
X210596Y431445D03*
X199590Y434639D03*
X201190Y442389D03*
X201300Y519750D03*
X201000Y515300D03*
X211150Y520500D03*
X207000Y600000D03*
X261250Y588500D03*
X211000Y585600D03*
X196261Y807853D03*
X261500Y1042000D03*
X211000Y1038200D03*
X201800Y972750D03*
X201600Y968400D03*
X210850Y973800D03*
X208000Y1053000D03*
X244829Y1241403D03*
X218384Y1411500D03*
X325800Y67250D03*
X308500Y80000D03*
X316800Y84000D03*
X325900Y62900D03*
X335100Y67800D03*
X331500Y147500D03*
X384549Y126350D03*
X317500Y148000D03*
X335299Y133000D03*
X320474Y364117D03*
X316534Y341619D03*
X294542Y376650D03*
X294000Y366300D03*
X305400Y317825D03*
X325800Y519750D03*
X308500Y532500D03*
X320958Y533200D03*
X325800Y514700D03*
X335050Y520700D03*
X331500Y600000D03*
X385750Y588500D03*
X317500Y600500D03*
X335290Y585300D03*
X294542Y829350D03*
X320474Y812669D03*
X316534Y790171D03*
X294000Y819000D03*
X305400Y764768D03*
X312418Y868254D03*
X385750Y1041500D03*
X335100Y1038500D03*
X325800Y972750D03*
X308500Y985500D03*
X317542Y988731D03*
X325600Y968400D03*
X334750Y973200D03*
X331500Y1053000D03*
X317500Y1053500D03*
X372774Y1438648D03*
X459000Y57500D03*
X448200Y40150D03*
X445500Y74300D03*
X459511Y44500D03*
X458900Y76700D03*
X455500Y147500D03*
X441500Y148000D03*
X459400Y133100D03*
X429900Y278468D03*
X444687Y358540D03*
X440747Y336042D03*
X419042Y376350D03*
X418500Y366000D03*
X435190Y408695D03*
X449800Y519750D03*
X432500Y532500D03*
X440855Y536014D03*
X449800Y515400D03*
X459350Y520600D03*
X455500Y600000D03*
X441500Y600500D03*
X459500Y585400D03*
X429600Y761281D03*
X418742Y828794D03*
X444687Y807662D03*
X440747Y785164D03*
X415000Y819000D03*
X448289Y917775D03*
X434890Y861395D03*
X459100Y1038400D03*
X449800Y972750D03*
X432500Y985500D03*
X441398Y989368D03*
X449700Y968500D03*
X459150Y973500D03*
X455500Y1053000D03*
X441500Y1053500D03*
X478444Y1240034D03*
X428500Y1423500D03*
Y1430500D03*
X574300Y67250D03*
X557000Y80000D03*
X565757Y83609D03*
X574300Y62900D03*
X508761Y126250D03*
X566000Y148000D03*
X548228Y100997D03*
X536715Y271785D03*
X568899Y355752D03*
X564959Y333254D03*
X493899Y320895D03*
X488448Y338766D03*
X482745Y351821D03*
X543242Y376650D03*
X498968Y296814D03*
X505052Y368552D03*
X511136Y352328D03*
X517473Y332556D03*
X523810Y312530D03*
X531987Y294450D03*
X554100Y294300D03*
X557975Y412093D03*
X574300Y519750D03*
X557000Y532500D03*
X565500Y537000D03*
X574300Y515500D03*
X509750Y588500D03*
X566000Y600500D03*
X569000Y814761D03*
X564959Y791755D03*
X575148Y827910D03*
X509750Y1041500D03*
X574300Y972750D03*
X557000Y985500D03*
X566574Y988327D03*
X574200Y968300D03*
X566000Y1053500D03*
X547198Y1420600D03*
X497000Y1408500D03*
X539500Y1408000D03*
X553500D03*
X572000D03*
X583700Y68200D03*
X580000Y147500D03*
X632974Y126250D03*
X583724Y132900D03*
X665100Y275593D03*
X654242Y376350D03*
X653700Y366000D03*
X670390Y408695D03*
X583550Y520300D03*
Y508800D03*
X672050Y552553D03*
X580000Y600000D03*
X634250Y588500D03*
X583600Y585200D03*
X646680Y647138D03*
X582648Y829573D03*
X659642Y829050D03*
X652142Y822416D03*
X593680Y827400D03*
X670500Y829616D03*
X594056Y909112D03*
X598970Y862595D03*
X610207Y900960D03*
X634250Y1041500D03*
X583600Y1038500D03*
X583050Y973400D03*
X671359Y1006366D03*
X580000Y1053000D03*
X607000Y1291500D03*
X663263Y1427653D03*
X590500Y1408500D03*
X646226Y1433033D03*
X663109Y1433549D03*
X663726Y1438933D03*
X672500Y1485000D03*
X667500Y1476250D03*
X707937Y57400D03*
X687700Y79300D03*
X692250Y74000D03*
X710000Y44500D03*
X707937Y73750D03*
X701300Y147700D03*
X690000Y148000D03*
X707937Y132800D03*
X693112Y342443D03*
X689172Y319945D03*
X698300Y519750D03*
X681000Y532500D03*
X690116Y535877D03*
X698100Y515100D03*
X707800Y520800D03*
X703200Y512000D03*
X704000Y600000D03*
X757300Y582800D03*
X690000Y600500D03*
X707900Y585200D03*
X749541Y717011D03*
X685500Y773631D03*
X680500Y790616D03*
X758562Y925283D03*
X675790Y861395D03*
X740364Y901060D03*
X758250Y1043000D03*
X707800Y1038200D03*
X698300Y972750D03*
X681000Y985500D03*
X690141Y989210D03*
X698000Y968300D03*
X707450Y973600D03*
X704000Y1053000D03*
X690000Y1053500D03*
X745367Y1239122D03*
X703411Y1387198D03*
X744132Y1426834D03*
X719000Y1453500D03*
X701000Y1438000D03*
X708500Y1438500D03*
X706000Y1453500D03*
X684750Y1435250D03*
X692750Y1435500D03*
X673500Y1448500D03*
X687900Y1471800D03*
X704000Y1469800D03*
X705890Y1446000D03*
X676500Y1472150D03*
X698500Y1431000D03*
X673964Y1434848D03*
X734032Y1465634D03*
X705500Y1463000D03*
X711363Y1458500D03*
X746064Y1494250D03*
X752132Y1450534D03*
X745406Y1486450D03*
X750232Y1472534D03*
X739532Y1430734D03*
X730332Y1457534D03*
X748732Y1460134D03*
X845968Y380023D03*
X842786Y374795D03*
X836451Y444751D03*
X844585Y451535D03*
X829490Y657790D03*
X830990Y652690D03*
X829490Y647190D03*
X816068Y625673D03*
X796484Y648490D03*
X800684Y652390D03*
X805128Y646475D03*
X862500Y760000D03*
X817373Y744099D03*
X816104Y679776D03*
X806535Y676210D03*
X831000Y817600D03*
X861986Y804305D03*
X832500Y812500D03*
X830000Y807000D03*
X824500Y775000D03*
X824000Y769000D03*
X863100Y765200D03*
X862600Y769500D03*
X824500Y780500D03*
X819870Y932430D03*
X824970Y933930D03*
X830300Y932470D03*
X832000Y887000D03*
Y881500D03*
X796396Y879084D03*
X785560Y876549D03*
X844940Y915701D03*
X768449Y929466D03*
X769130Y919152D03*
X853398Y914258D03*
X860219Y912294D03*
X833500Y895500D03*
X859200Y891900D03*
X830470Y970430D03*
X822430Y968470D03*
X834871Y966706D03*
X814330Y1026361D03*
X810751Y1028560D03*
X797473Y1041318D03*
X844120Y974180D03*
X779222Y1116604D03*
X802162Y1075032D03*
X771236Y1096959D03*
X810000Y1327000D03*
X810500Y1377000D03*
X817277Y1402673D03*
X847000Y1407000D03*
X838500D03*
X852493Y1392918D03*
X945656Y547005D03*
X951860Y524737D03*
X951739Y530020D03*
X951915Y556600D03*
X866276Y650103D03*
X865530Y655230D03*
X892391Y622635D03*
X898676Y631324D03*
X865945Y643688D03*
X875007Y601293D03*
X916951Y757250D03*
X917600Y778500D03*
X955482Y772968D03*
Y778168D03*
Y767768D03*
X917700Y774200D03*
Y769200D03*
X946167Y853833D03*
X952500Y854500D03*
X957095Y854128D03*
X935250Y854000D03*
X940000D03*
X869000Y807000D03*
X867040Y815040D03*
X883750Y822250D03*
X874562Y825063D03*
X913597Y800899D03*
X906008Y799372D03*
X917211Y793314D03*
X908543Y792632D03*
X917211Y788194D03*
X917600Y783500D03*
X896283Y829425D03*
X886342Y834927D03*
X888100Y827700D03*
X880209Y831210D03*
X920461Y824079D03*
X917052Y831472D03*
X953742Y818977D03*
X941564Y821964D03*
X920170Y849500D03*
X925073Y840417D03*
X909940Y871500D03*
X918380Y911780D03*
X913000Y911500D03*
X923645Y911630D03*
X915250Y870750D03*
X920712Y870212D03*
X867700Y873500D03*
Y878200D03*
X867350Y883000D03*
X895346Y871309D03*
X900346D03*
X902749Y864327D03*
X898596Y858067D03*
X954208Y894134D03*
X949371Y898442D03*
X923468Y875044D03*
X940499Y905125D03*
X951500Y1222500D03*
X943500Y1221000D03*
X899919Y1176183D03*
X934200Y1190700D03*
X934271Y1198029D03*
X942955Y1200945D03*
X940168Y1211332D03*
X868900Y1192600D03*
X885118Y1202182D03*
X931900Y1206220D03*
X927500Y1211340D03*
X933200Y1216460D03*
X869937Y1395977D03*
X953652Y1420748D03*
X1026521Y387770D03*
X1036100Y410500D03*
X1045300Y420400D03*
X1033200Y423228D03*
X1017500Y426131D03*
X1047900Y432500D03*
X1041600Y435700D03*
X980100Y413700D03*
X1005846Y429434D03*
X1016557Y437230D03*
X995633Y547651D03*
X1004460Y533819D03*
X981500Y512300D03*
X984200Y539000D03*
X1015143Y577288D03*
X1003166Y574208D03*
X1011037Y736868D03*
X1015618Y700908D03*
X1019284Y721708D03*
X1023243Y732861D03*
X1028089Y707561D03*
X1032654Y697436D03*
X979107Y839078D03*
X974163Y839165D03*
X983000Y837500D03*
X989120D03*
X1005450Y849166D03*
X999500Y849500D03*
X1033807Y847865D03*
X989933Y872000D03*
X982500Y871400D03*
X971982Y873647D03*
X983311Y904195D03*
X978033Y902083D03*
X972854Y900520D03*
X964170Y895500D03*
X993483Y899206D03*
X1039500Y878500D03*
X1004300Y889275D03*
X1009800Y887100D03*
X1016400Y886500D03*
X1021500D03*
X1028500Y862000D03*
X1003000Y916000D03*
X1025500Y919500D03*
X987300Y1179800D03*
X982172Y1176631D03*
X959500Y1221000D03*
X970500Y1205000D03*
X972000Y1223400D03*
Y1201000D03*
X970500Y1197000D03*
X967500Y1221000D03*
X972000Y1209000D03*
X970500Y1213000D03*
X963500Y1222500D03*
X1035882Y1327084D03*
X981700Y1315900D03*
X1045536Y1316578D03*
X975332Y1239578D03*
X1035676Y1383286D03*
X1036877Y1356115D03*
X1008443Y1425899D03*
X1015943Y1426399D03*
X1035100Y1397300D03*
X970552Y1421448D03*
X971169Y1426832D03*
X992800Y1422300D03*
X1000193Y1423399D03*
X979900Y1426800D03*
X1005943Y1418899D03*
X987600Y1425200D03*
X994884Y1393370D03*
X1049437Y1367213D03*
X1048400Y1339700D03*
X1036918Y1391589D03*
X1052485Y1421680D03*
X1018943Y1438899D03*
X979599Y1436399D03*
X995617Y1459516D03*
X1021618Y1460000D03*
X1013333Y1433899D03*
X979179Y1450158D03*
X1015550Y1496214D03*
X1028650Y1494714D03*
X1039450Y1501914D03*
X1037350Y1487714D03*
X1046850Y1485514D03*
X1050050Y1496014D03*
X966465Y1454578D03*
X966438Y1450158D03*
X1015443Y1452399D03*
X1016943Y1446320D03*
X973617Y1445912D03*
Y1440912D03*
X1035943Y1436649D03*
X1067872Y422624D03*
X1074400Y419124D03*
X1120959Y621993D03*
X1063591Y1008944D03*
X1056428Y998612D03*
X1059569Y1017555D03*
X1093332Y1037457D03*
X1124848Y1034859D03*
X1087100Y1304820D03*
X1086062Y1294580D03*
X1085962Y1309495D03*
X1055536Y1393731D03*
X1063920Y1385019D03*
X1130112Y1374773D03*
X1123037Y1374473D03*
X1111012Y1391273D03*
X1109612Y1371600D03*
Y1395273D03*
X1111112Y1399273D03*
X1114112Y1374773D03*
X1109612Y1387273D03*
X1111112Y1383273D03*
X1118301Y1374458D03*
X1138112Y1375273D03*
X1100300Y1359247D03*
X1133412Y1407173D03*
X1141554Y1399660D03*
X1147312Y1387193D03*
X1147512Y1382073D03*
X1144564Y1392821D03*
X1140175Y1389710D03*
X1140512Y1381273D03*
X1112673Y1500348D03*
X1242718Y335091D03*
X1238778Y312593D03*
X1234254Y442080D03*
X1216078Y465349D03*
X1232660Y453858D03*
X1188800Y507600D03*
X1216040Y625269D03*
X1207265Y709641D03*
X1212703Y758435D03*
X1206937Y755002D03*
X1214657Y681090D03*
X1232675Y738300D03*
X1217111Y829350D03*
X1242718Y820846D03*
X1238778Y798348D03*
X1216569Y819000D03*
X1189224Y912756D03*
X1188509Y918850D03*
X1160314Y1032608D03*
X1223634Y1052998D03*
X1211764Y1320310D03*
X1172318Y1320640D03*
X1218529Y1242316D03*
X1197394Y1298415D03*
X1230600D03*
X1202394D03*
X1235600D03*
X1192394D03*
X1225600D03*
X1202394Y1335151D03*
X1235600D03*
X1192394D03*
X1225600D03*
X1187394D03*
X1220600D03*
X1197394D03*
X1230600D03*
X1212460Y1422825D03*
X1209500Y1397433D03*
X1306950Y59950D03*
X1312100Y58300D03*
X1313000Y41750D03*
X1307000Y166100D03*
X1257533Y126350D03*
X1324900Y154100D03*
X1310500Y133000D03*
X1334250Y104300D03*
X1257000Y355500D03*
X1261060Y300000D03*
X1338423Y429770D03*
X1248784Y442826D03*
X1317000Y517000D03*
X1336500Y533500D03*
X1306800Y525500D03*
X1324500Y533500D03*
X1317000Y508250D03*
X1307100Y618800D03*
X1257500Y579050D03*
X1334000Y616500D03*
X1310500Y586000D03*
X1340324Y928894D03*
X1257100Y1031750D03*
X1310500Y1038500D03*
X1317000Y969500D03*
X1337500Y986000D03*
X1307850Y977800D03*
X1324500Y986000D03*
X1317000Y960750D03*
X1307100Y1071600D03*
X1334000Y1069000D03*
X1305500Y1413500D03*
X1324000Y1412600D03*
X1281624Y1425618D03*
X1277624Y1416318D03*
X1279484Y1471500D03*
X1255974Y1484800D03*
X1259374Y1501400D03*
X1269974Y1469300D03*
X1251574Y1490800D03*
X1270574Y1493300D03*
X1262774Y1449300D03*
X1257874Y1450500D03*
X1252274Y1477000D03*
X1270674Y1479500D03*
X1431300Y72150D03*
X1431100Y166000D03*
X1381756Y126350D03*
X1434500Y133000D03*
X1364600Y189600D03*
X1366931Y359435D03*
X1362991Y336937D03*
X1342880Y363931D03*
X1358498Y307500D03*
X1431350Y525000D03*
X1344024Y483916D03*
X1431300Y618900D03*
X1381600Y579200D03*
X1434500Y586000D03*
X1350982Y737700D03*
X1341324Y829350D03*
X1366931Y820844D03*
X1362991Y798346D03*
X1354742Y764100D03*
X1381500Y1031800D03*
X1434500Y1038500D03*
X1431350Y978200D03*
X1431313Y1071600D03*
X1341268Y1326727D03*
X1386424Y1415469D03*
X1365374Y1412500D03*
X1441000Y64000D03*
X1460500Y80500D03*
X1441200Y68200D03*
X1441000Y55250D03*
X1505968Y126350D03*
X1458000Y163500D03*
X1449286Y109468D03*
X1453052Y199552D03*
X1491143Y364938D03*
X1487203Y342440D03*
X1464994Y366244D03*
X1478954Y299400D03*
X1462350Y428169D03*
X1441000Y517000D03*
X1460500Y533500D03*
X1448500D03*
X1441000Y508250D03*
X1465195Y482118D03*
X1449416Y562671D03*
X1505900Y578800D03*
X1458000Y616500D03*
X1465536Y829350D03*
X1491143Y821350D03*
X1487203Y798852D03*
X1464994Y819000D03*
X1476400Y827900D03*
X1472646Y930795D03*
X1505700Y1031850D03*
X1441000Y969500D03*
X1461500Y986000D03*
X1448500D03*
X1441000Y960750D03*
X1458000Y1069000D03*
X1483629Y1240035D03*
X1562500Y50500D03*
X1576800Y69000D03*
X1555450Y59500D03*
X1563500Y61000D03*
X1562500Y41750D03*
X1555400Y166000D03*
X1568900Y148700D03*
X1559000Y133000D03*
X1615356Y363164D03*
X1611416Y340666D03*
X1589207Y366244D03*
X1603167Y304800D03*
X1578333Y431523D03*
X1587023Y474261D03*
X1565500Y517000D03*
X1585000Y533500D03*
X1555450Y524900D03*
X1573000Y533500D03*
X1565500Y508250D03*
X1555500Y618800D03*
X1582500Y616500D03*
X1559000Y586000D03*
X1589749Y829350D03*
X1615356Y822490D03*
X1611416Y799992D03*
X1597607Y763144D03*
X1600607Y824639D03*
X1607884Y925219D03*
X1559000Y1038500D03*
X1565500Y969500D03*
X1586000Y986000D03*
X1555750Y978600D03*
X1573000Y986000D03*
X1565500Y960750D03*
X1574019Y1015221D03*
X1555525Y1071600D03*
X1582500Y1069000D03*
X1689500Y64000D03*
X1709000Y80500D03*
X1679600Y72500D03*
X1697000Y80500D03*
X1689500Y55250D03*
X1679600Y166100D03*
X1630181Y126350D03*
X1706500Y163500D03*
X1683000Y133000D03*
X1697942Y109938D03*
X1720159Y475807D03*
X1721381Y411596D03*
X1717859Y460107D03*
X1711909Y470207D03*
X1706359Y441207D03*
X1689500Y517000D03*
X1709000Y533500D03*
X1680050Y525200D03*
X1697000Y533500D03*
X1689500Y508250D03*
X1701720Y497999D03*
X1698111Y562671D03*
X1679488Y618800D03*
X1630100Y579050D03*
X1706500Y616500D03*
X1683000Y586000D03*
X1713961Y829350D03*
X1629800Y1031850D03*
X1683000Y1038500D03*
X1689500Y969500D03*
X1709000Y986000D03*
X1679650Y978000D03*
X1697000Y986000D03*
X1689500Y960750D03*
X1697864Y1015165D03*
X1679738Y1071600D03*
X1706500Y1069000D03*
X1694626Y1414000D03*
X1712126Y1412600D03*
X1651906Y1447500D03*
X1659906Y1435500D03*
X1803200Y70600D03*
X1804800Y63100D03*
X1811800Y17700D03*
X1803900Y46100D03*
X1808200D03*
X1804000Y166100D03*
X1754300Y125900D03*
X1807000Y133000D03*
X1739568Y361896D03*
X1735628Y339398D03*
X1749650Y376854D03*
X1804600Y365600D03*
X1763791Y374891D03*
X1786451Y408530D03*
X1751774Y434652D03*
X1743359Y438057D03*
X1743959Y445807D03*
X1813500Y517000D03*
X1804050Y525100D03*
X1813500Y508250D03*
X1737859Y478707D03*
X1726859D03*
X1803700Y618800D03*
X1763000Y589000D03*
X1807000Y586000D03*
X1739568Y828517D03*
X1735628Y802019D03*
X1723619Y777600D03*
X1727379Y764235D03*
X1794563Y910125D03*
X1726771Y922050D03*
X1812263Y913025D03*
X1801263D03*
X1792263Y894425D03*
X1816263Y872375D03*
X1786313Y904525D03*
X1817863Y880125D03*
X1780763Y875525D03*
X1754300Y1031850D03*
X1807000Y1038500D03*
X1813500Y969500D03*
X1803750Y978100D03*
X1813500Y960750D03*
X1803950Y1071600D03*
X1729500Y1312000D03*
X1765596Y1414627D03*
X1748126Y1411500D03*
X1807626Y1485700D03*
X1797426Y1470400D03*
X1813826Y1471000D03*
X1800326Y1449600D03*
X1794426Y1450328D03*
X1799626Y1489800D03*
X1802526Y1471300D03*
X1874500Y73700D03*
X1822428Y77200D03*
X1878600Y24150D03*
X1862900Y34200D03*
X1862750Y73500D03*
X1818900Y88800D03*
X1878700Y19000D03*
X1876700Y42250D03*
X1835000Y25500D03*
Y20700D03*
X1874000Y146000D03*
X1830500Y163500D03*
X1860500Y147500D03*
X1878600Y132600D03*
X1830000Y101000D03*
X1836769Y355648D03*
X1839077Y346085D03*
X1852223Y303000D03*
X1876150Y525950D03*
X1853250Y522200D03*
X1833000Y533500D03*
X1857500Y558000D03*
X1859250Y531162D03*
X1821000Y533500D03*
X1849750Y518000D03*
X1858000Y510750D03*
X1860109Y497977D03*
X1874000Y599000D03*
X1830500Y616500D03*
X1860500Y600500D03*
X1878600Y585100D03*
X1846032Y746970D03*
X1838174Y829350D03*
X1863781Y821477D03*
X1859841Y798979D03*
X1849032Y827393D03*
X1866318Y948540D03*
X1827763Y869025D03*
X1871900Y988200D03*
X1878300Y1038300D03*
X1853250Y975200D03*
X1834000Y986000D03*
X1857500Y1010000D03*
X1859250Y983276D03*
X1821000Y986000D03*
X1849750Y971000D03*
X1858000Y963750D03*
X1874000Y1052000D03*
X1830500Y1069000D03*
X1860500Y1053500D03*
X1825059Y1476665D03*
X1825826Y1486750D03*
G54D24*
X67800Y95000D03*
Y547500D03*
Y1000500D03*
X148100Y25200D03*
X191800Y547500D03*
X111228Y873035D03*
X192300Y1000500D03*
X209055Y435299D03*
X316300Y95000D03*
Y547500D03*
Y1000500D03*
X440300Y547500D03*
Y1000500D03*
X405800Y1408000D03*
X564800Y95000D03*
Y547500D03*
Y1000500D03*
X510800Y1474500D03*
X528500Y1448100D03*
X688800Y547500D03*
Y1000500D03*
X943800Y890000D03*
X1013300Y846500D03*
X1004107Y895075D03*
X993724Y891165D03*
X1117412Y1402773D03*
X1305100Y63900D03*
X1306900Y534000D03*
X1307900Y986200D03*
X1431400Y533900D03*
Y986400D03*
X1555500Y63300D03*
Y533800D03*
X1555800Y986600D03*
X1680100Y534100D03*
X1679700Y986300D03*
X1814900Y24800D03*
X1751824Y438717D03*
X1804100Y534100D03*
X1763300Y579500D03*
X1803800Y986200D03*
X1859300Y547500D03*
X1826228Y873035D03*
X1859300Y1000500D03*
G54D51*
X184874Y1420050D03*
X107474Y1462200D03*
X198800Y41000D03*
X440400Y39300D03*
X524211Y1432734D03*
X669761Y1457300D03*
X695600Y40900D03*
X834470Y940730D03*
X924000Y885300D03*
X951569Y1403232D03*
X950339Y1390603D03*
X1002118Y1467665D03*
X978443Y1445199D03*
X1125615Y1314870D03*
X1175800Y1312700D03*
X1208933Y1312744D03*
X1200962Y1409402D03*
X1324000Y1420050D03*
X1712126D03*
X1803100Y78600D03*
G54D42*
X111024Y27697D03*
Y199941D03*
Y480453D03*
Y652697D03*
Y933209D03*
Y1105453D03*
X235236Y27697D03*
Y199941D03*
Y480453D03*
Y652697D03*
Y933209D03*
Y1105453D03*
X359449Y27697D03*
Y199941D03*
Y480453D03*
Y652697D03*
Y933209D03*
Y1105453D03*
X483661Y27697D03*
Y199941D03*
Y480453D03*
Y652697D03*
Y933209D03*
Y1105453D03*
X607874Y27697D03*
Y199941D03*
Y480453D03*
Y652697D03*
Y933209D03*
Y1105453D03*
X732087Y27697D03*
Y199941D03*
Y480453D03*
Y652697D03*
Y933209D03*
Y1105453D03*
X957000Y1207500D03*
X1124612Y1388773D03*
X1281693Y27697D03*
Y199941D03*
Y480453D03*
Y652697D03*
Y933209D03*
Y1105453D03*
X1405906Y27697D03*
Y199941D03*
Y480453D03*
Y652697D03*
Y933209D03*
Y1105453D03*
X1530118Y27697D03*
Y199941D03*
Y480453D03*
Y652697D03*
Y933209D03*
Y1105453D03*
X1654331Y27697D03*
Y199941D03*
Y480453D03*
Y652697D03*
Y933209D03*
Y1105453D03*
X1778543Y27697D03*
Y199941D03*
Y480453D03*
Y652697D03*
Y933209D03*
Y1105453D03*
X1902756Y27697D03*
Y199941D03*
Y480453D03*
Y652697D03*
Y933209D03*
Y1105453D03*
G54D33*
X93500Y136500D03*
Y125500D03*
Y589000D03*
Y578000D03*
Y1042000D03*
Y1031000D03*
X217500Y136500D03*
Y125500D03*
Y589000D03*
Y578000D03*
X218000Y1042000D03*
Y1031000D03*
X342000Y136500D03*
Y125500D03*
Y589000D03*
Y578000D03*
Y1042000D03*
Y1031000D03*
X466000Y136500D03*
Y125500D03*
Y589000D03*
Y578000D03*
Y1042000D03*
Y1031000D03*
X590500Y136500D03*
Y125500D03*
Y589000D03*
Y578000D03*
Y1042000D03*
Y1031000D03*
X714500Y136500D03*
Y125500D03*
Y589000D03*
Y578000D03*
Y1042000D03*
Y1031000D03*
X1308500Y150500D03*
Y139500D03*
Y603500D03*
Y592500D03*
Y1045000D03*
Y1056000D03*
X1432500Y150500D03*
Y139500D03*
Y603500D03*
Y592500D03*
Y1045000D03*
Y1056000D03*
X1557000Y150500D03*
Y139500D03*
Y603500D03*
Y592500D03*
Y1045000D03*
Y1056000D03*
X1681000Y150500D03*
Y139500D03*
Y603500D03*
Y592500D03*
Y1045000D03*
Y1056000D03*
X1805000Y150500D03*
Y139500D03*
Y603500D03*
Y592500D03*
Y1045000D03*
Y1056000D03*
X1885000Y136000D03*
Y125000D03*
Y589000D03*
Y578000D03*
Y1042000D03*
Y1031000D03*
G54D15*
X92200Y72400D03*
X89000Y62800D03*
X60200Y96500D03*
X58659Y383528D03*
X73392Y403305D03*
X92000Y525300D03*
X90300Y516800D03*
X60200Y549000D03*
X46392Y836182D03*
X61125Y855959D03*
X97963Y908025D03*
X97055Y899023D03*
X89597Y901301D03*
X74763Y909325D03*
X73463Y892025D03*
X60200Y1002000D03*
X92200Y968000D03*
Y972500D03*
X164200Y25100D03*
X160500Y32100D03*
X175600Y25100D03*
X164200Y21100D03*
X175600Y20900D03*
X171800Y29200D03*
X147500Y44400D03*
Y48500D03*
X194882Y461287D03*
X187424Y463565D03*
X172590Y471589D03*
X171290Y454289D03*
X192792Y383182D03*
X184200Y549000D03*
X140700Y583000D03*
X184125Y855659D03*
X109763Y911925D03*
X109722Y903550D03*
X140700Y1036000D03*
X184700Y1002000D03*
X141174Y1472900D03*
X142074Y1452500D03*
Y1434000D03*
X128274Y1479100D03*
X198700Y78500D03*
X207200Y45100D03*
X207590Y474189D03*
X195790Y470289D03*
X207549Y465814D03*
X207525Y402959D03*
X216100Y525200D03*
X214600Y516600D03*
X264700Y583000D03*
X214300Y969700D03*
X216700Y978100D03*
X264400Y1036000D03*
X340600Y72600D03*
X338400Y63700D03*
X308700Y96500D03*
X294492Y383482D03*
X309225Y403259D03*
X340700Y525300D03*
X338500Y516800D03*
X308700Y549000D03*
X294492Y836182D03*
X309225Y855959D03*
X308700Y1002000D03*
X338200Y969400D03*
X340600Y978200D03*
X455400Y44500D03*
X418992Y383182D03*
X433725Y402959D03*
X464700Y525300D03*
X462800Y516900D03*
X432700Y549000D03*
X389200Y583000D03*
X418692Y835876D03*
X433425Y855659D03*
X389200Y1036000D03*
X432700Y1002000D03*
X462600Y969200D03*
X464600Y978000D03*
X557200Y96500D03*
X543192Y383482D03*
X557925Y403259D03*
X557200Y549000D03*
X513200Y583000D03*
Y1036000D03*
X557200Y1002000D03*
X589100Y72800D03*
X587200Y64300D03*
X654192Y383182D03*
X668925Y402959D03*
X589100Y525400D03*
X637700Y583000D03*
X659592Y835882D03*
X582598Y836405D03*
X597505Y856859D03*
X586500Y969500D03*
X589200Y978100D03*
X637700Y1036000D03*
X671700Y1430000D03*
X695700Y78500D03*
X704700Y45050D03*
X751700Y130500D03*
X713100Y525300D03*
X681200Y549000D03*
X674325Y855659D03*
X681200Y1002000D03*
X710900Y969600D03*
X713300Y978300D03*
X753100Y1036000D03*
X714200Y1453500D03*
X715500Y1467300D03*
X727200Y1449000D03*
X715600Y1471600D03*
X824690Y659190D03*
Y647190D03*
Y651190D03*
X818000Y776500D03*
X817900Y785500D03*
X818000Y767500D03*
X826200Y819000D03*
Y807000D03*
Y811000D03*
X827700Y897500D03*
Y888500D03*
X827587Y880256D03*
X874690Y643190D03*
Y651190D03*
X870500Y756500D03*
X878353Y811000D03*
X876200Y803000D03*
X919500Y764800D03*
X912200Y774000D03*
Y778000D03*
X875700Y869500D03*
X958200Y898500D03*
X944200D03*
X958750Y1403400D03*
Y1399400D03*
X992948Y539555D03*
X995138Y517437D03*
X999541Y552081D03*
X995163Y526457D03*
X963820Y761010D03*
Y779010D03*
Y765510D03*
X1037581Y855984D03*
X1023700Y842500D03*
X1037584Y851705D03*
X1029862Y849214D03*
X1033042Y825127D03*
X1004007Y899075D03*
X993597Y895065D03*
X1011481Y903075D03*
X1021739Y900965D03*
X1027474Y939306D03*
X979200Y1225000D03*
Y1205000D03*
Y1221000D03*
Y1213000D03*
X979143Y1418699D03*
X1037550Y1496914D03*
X1023950Y1492814D03*
X1045250D03*
X1037550D03*
X1130200Y1291700D03*
Y1296700D03*
X1105812Y1379273D03*
Y1399273D03*
Y1395273D03*
Y1387273D03*
X1115200Y1358500D03*
X1217061Y836182D03*
X1231794Y855959D03*
X1188200Y892600D03*
Y886000D03*
Y906100D03*
Y899500D03*
X1334200Y109500D03*
X1262895Y383269D03*
X1277628Y403046D03*
X1335200Y562500D03*
Y1015000D03*
X1288074Y1471500D03*
X1289074Y1452500D03*
Y1434000D03*
X1274789Y1483400D03*
X1435700Y77000D03*
X1341274Y383426D03*
X1356007Y403203D03*
X1341274Y836182D03*
X1356007Y855959D03*
X1459200Y109500D03*
X1465486Y383426D03*
X1480219Y403203D03*
X1459200Y562500D03*
X1465486Y836182D03*
X1480219Y855959D03*
X1459200Y1015000D03*
X1604600Y129000D03*
X1589699Y383426D03*
X1604432Y403203D03*
X1583700Y562500D03*
X1589699Y836182D03*
X1604432Y855959D03*
X1583700Y1015000D03*
X1707700Y109500D03*
X1715359Y475007D03*
X1714059Y457707D03*
X1707700Y562500D03*
X1713911Y836182D03*
X1707700Y1015000D03*
X1669326Y1452500D03*
Y1434000D03*
X1816200Y64400D03*
X1738559Y473707D03*
X1750318Y469232D03*
X1737651Y464705D03*
X1730193Y466983D03*
X1805092Y383782D03*
X1753392Y402630D03*
X1767601Y402301D03*
X1750359Y477607D03*
X1728644Y855959D03*
X1812963Y908025D03*
X1812055Y899023D03*
X1804597Y901301D03*
X1789763Y909325D03*
X1788463Y892025D03*
X1806841Y1490100D03*
X1809811Y1471000D03*
X1822378Y85039D03*
Y80939D03*
X1881700Y77500D03*
X1866200Y78000D03*
X1867400Y38100D03*
X1825300Y32000D03*
X1830900Y25100D03*
Y20900D03*
X1838400Y29300D03*
X1842300Y25200D03*
Y21100D03*
X1830700Y109500D03*
X1819825Y403559D03*
X1831700Y562500D03*
X1879600Y530600D03*
X1851700Y549000D03*
X1853200Y527000D03*
X1838124Y836182D03*
X1852857Y855959D03*
X1824763Y911925D03*
X1824722Y903550D03*
X1831700Y1015000D03*
X1851700Y1002000D03*
X1853200Y980000D03*
G54D60*
X537234Y1422529D03*
Y1434129D03*
G54D25*
X64200Y95000D03*
Y547500D03*
Y1000500D03*
X144500Y25200D03*
X188200Y547500D03*
X107628Y873035D03*
X188700Y1000500D03*
X205455Y435299D03*
X312700Y95000D03*
Y547500D03*
Y1000500D03*
X436700Y547500D03*
Y1000500D03*
X402200Y1408000D03*
X561200Y95000D03*
Y547500D03*
Y1000500D03*
X507200Y1474500D03*
X524900Y1448100D03*
X685200Y547500D03*
Y1000500D03*
X940200Y890000D03*
X1009700Y846500D03*
X1000507Y895075D03*
X990124Y891165D03*
X1113812Y1402773D03*
X1301500Y63900D03*
X1303300Y534000D03*
X1304300Y986200D03*
X1427800Y533900D03*
Y986400D03*
X1551900Y63300D03*
Y533800D03*
X1552200Y986600D03*
X1676500Y534100D03*
X1676100Y986300D03*
X1811300Y24800D03*
X1748224Y438717D03*
X1800500Y534100D03*
X1759700Y579500D03*
X1800200Y986200D03*
X1855700Y547500D03*
X1822628Y873035D03*
X1855700Y1000500D03*
G54D34*
X61800Y140500D03*
X54200D03*
X61800Y593000D03*
X54200D03*
X72490Y881867D03*
X80090D03*
X72490Y874206D03*
X80090D03*
X87194Y872375D03*
X94794D03*
X61800Y1046000D03*
X54200D03*
X86624Y1465850D03*
X94224D03*
X94324Y1473650D03*
X86724D03*
X185800Y140500D03*
X178200D03*
X170317Y444131D03*
X177917D03*
X170317Y436470D03*
X177917D03*
X185021Y434639D03*
X192621D03*
X185800Y593000D03*
X178200D03*
X186300Y1046000D03*
X178700D03*
X310300Y140500D03*
X302700D03*
X310300Y593000D03*
X302700D03*
X310300Y1046000D03*
X302700D03*
X434300Y140500D03*
X426700D03*
X434300Y593000D03*
X426700D03*
X434300Y1046000D03*
X426700D03*
X558800Y140500D03*
X551200D03*
X558800Y593000D03*
X551200D03*
X558800Y1046000D03*
X551200D03*
X682800Y140500D03*
X675200D03*
X682800Y593000D03*
X675200D03*
X682800Y1046000D03*
X675200D03*
X731350Y1486450D03*
X738950D03*
Y1494250D03*
X731350D03*
X817800Y1333000D03*
X810200D03*
X847295Y1392884D03*
X839695D03*
X839656Y1400536D03*
X847256D03*
X830342Y1402656D03*
X822742D03*
X817800Y1371500D03*
X810200D03*
X1049568Y1327989D03*
X1041968D03*
X1041818Y1391589D03*
X1049418D03*
Y1399389D03*
X1041818D03*
X1049568Y1355789D03*
X1041968D03*
X1049568Y1383589D03*
X1041968D03*
X1125673Y1493448D03*
X1118073D03*
X1234874Y1465500D03*
X1242474D03*
Y1473200D03*
X1234874D03*
X1713086Y447549D03*
X1720686D03*
X1713086Y439888D03*
X1720686D03*
X1727790Y438057D03*
X1735390D03*
X1787490Y881867D03*
X1795090D03*
X1787490Y874206D03*
X1795090D03*
X1802194Y872375D03*
X1809794D03*
X1853300Y140000D03*
X1845700D03*
X1853300Y593000D03*
X1845700D03*
X1853300Y1046000D03*
X1845700D03*
X1842026Y1473350D03*
X1834426D03*
X1834526Y1465600D03*
X1842126D03*
G54D52*
X145445Y1425760D03*
Y1423200D03*
Y1420640D03*
X151945D03*
Y1425760D03*
G54D61*
X517500Y1471924D03*
Y1458624D03*
X535200Y1447950D03*
Y1461250D03*
G54D16*
X60000Y73200D03*
Y525700D03*
X81700Y905280D03*
X77563Y905225D03*
X60000Y978700D03*
X131600Y126100D03*
X179527Y467544D03*
X175390Y467489D03*
X184000Y525700D03*
X184500Y978700D03*
X138974Y1429100D03*
X149374Y1457200D03*
Y1438700D03*
X207000Y77200D03*
X217000Y45200D03*
X254900Y126300D03*
X308500Y73200D03*
X379500Y126300D03*
X308500Y525700D03*
Y978700D03*
X454000Y80600D03*
X465500Y45200D03*
X432500Y525700D03*
Y978700D03*
X557000Y73200D03*
X503900Y126200D03*
X557000Y525700D03*
Y978700D03*
X502999Y1451632D03*
X628000Y126200D03*
X583550Y516250D03*
X655795Y1429619D03*
X628500Y1464700D03*
X704000Y77200D03*
X714000Y45200D03*
X707800Y516900D03*
X681000Y525700D03*
X752200Y579000D03*
X681000Y978700D03*
X676500Y1479700D03*
X841939Y389815D03*
X846939D03*
X822470Y927630D03*
Y977630D03*
X830470D03*
X839970Y969870D03*
X955000Y547800D03*
X952100Y520000D03*
X922100Y760700D03*
X948500Y849200D03*
X953000D03*
X911080Y864070D03*
X918380Y919114D03*
X914260Y919070D03*
X951500Y1229700D03*
X868900Y1188200D03*
X888000Y1197300D03*
X986200Y547700D03*
X983300Y522000D03*
X966093Y849200D03*
X993942Y879500D03*
X976242Y881200D03*
X980442Y879500D03*
X1000500Y910700D03*
X1005500D03*
X959500Y1229700D03*
X963238Y1417518D03*
X998325Y1467634D03*
X1013618Y1467565D03*
X1043606Y1448349D03*
X975438Y1453608D03*
X1122112Y1369973D03*
X1134112D03*
X1114112D03*
X1118112D03*
X1138112D03*
X1203394Y1343483D03*
X1222100D03*
X1236600D03*
X1232100D03*
X1217100D03*
X1183894D03*
X1188894D03*
X1198894D03*
X1203487Y1424641D03*
X1308000Y41700D03*
X1318000D03*
X1317800Y54000D03*
X1311700Y69100D03*
X1313700Y54000D03*
X1262600Y126300D03*
X1312000Y508200D03*
X1322000D03*
X1326500Y520700D03*
X1322000D03*
X1262600Y579000D03*
X1262400Y1031700D03*
X1312000Y960700D03*
X1322000D03*
X1326500Y973200D03*
X1322000D03*
X1296374Y1457200D03*
Y1438700D03*
X1436000Y55200D03*
X1387200Y126300D03*
X1436000Y508200D03*
X1386400Y579000D03*
X1387000Y1031800D03*
X1436000Y960700D03*
X1446000Y55200D03*
X1450500Y67700D03*
X1446000D03*
X1511400Y126300D03*
X1446000Y508200D03*
X1450500Y520700D03*
X1446000D03*
X1511200Y579000D03*
X1446000Y960700D03*
X1450500Y973200D03*
X1446000D03*
X1511400Y1031800D03*
X1557500Y41700D03*
X1567500D03*
X1572000Y54200D03*
X1563500Y69200D03*
X1567500Y54200D03*
X1560500Y508200D03*
X1570500D03*
X1575000Y520700D03*
X1570500D03*
X1560500Y960700D03*
X1570500D03*
X1575000Y973200D03*
X1570500D03*
X1684500Y55200D03*
X1694500D03*
X1699000Y67700D03*
X1694500D03*
X1635300Y126300D03*
X1722296Y470962D03*
X1718159Y470907D03*
X1684500Y508200D03*
X1694500D03*
X1699000Y520700D03*
X1694500D03*
X1634200Y579000D03*
X1635100Y1031800D03*
X1684500Y960700D03*
X1694500D03*
X1699000Y973200D03*
X1694500D03*
X1676626Y1457200D03*
Y1438700D03*
X1759600Y126300D03*
X1808500Y508200D03*
X1792563Y905225D03*
X1796700Y905280D03*
X1759300Y1031800D03*
X1808500Y960700D03*
X1884600Y45700D03*
X1862300Y30000D03*
X1818500Y508200D03*
X1823000Y520700D03*
X1818500D03*
X1853000Y510700D03*
X1848500D03*
X1843000Y541200D03*
X1818500Y960700D03*
X1823000Y973200D03*
X1818500D03*
X1875800Y988200D03*
X1853000Y963700D03*
X1848500D03*
X1843000Y994200D03*
G54D43*
X126709Y57719D03*
X128909D03*
X126709Y59919D03*
X128909D03*
X126709Y510475D03*
X128909D03*
X126709Y512675D03*
X128909D03*
X126709Y963231D03*
X128909D03*
X126709Y965431D03*
X128909D03*
X250921Y57719D03*
X253121D03*
X250921Y59919D03*
X253121D03*
X250921Y510475D03*
X253121D03*
X250921Y512675D03*
X253121D03*
X250921Y963231D03*
X253121D03*
X250921Y965431D03*
X253121D03*
X375134Y57719D03*
X377334D03*
X375134Y59919D03*
X377334D03*
X375134Y510475D03*
X377334D03*
X375134Y512675D03*
X377334D03*
X375134Y963231D03*
X377334D03*
X375134Y965431D03*
X377334D03*
X499346Y57719D03*
X501546D03*
X499346Y59919D03*
X501546D03*
X499346Y510475D03*
X501546D03*
X499346Y512675D03*
X501546D03*
X499346Y963231D03*
X501546D03*
X499346Y965431D03*
X501546D03*
X623559Y57719D03*
X625759D03*
X623559Y59919D03*
X625759D03*
X623559Y510475D03*
X625759D03*
X623559Y512675D03*
X625759D03*
X623559Y965431D03*
X625759D03*
X623559Y963231D03*
X625759D03*
X747772Y57719D03*
X749972D03*
X747772Y59919D03*
X749972D03*
X747772Y510475D03*
X749972D03*
X747772Y512675D03*
X749972D03*
X747772Y965431D03*
X749972D03*
X747772Y963231D03*
X749972D03*
G54D70*
X814843Y403862D03*
Y424130D03*
X810400Y561866D03*
Y582134D03*
X801300Y1201766D03*
Y1222034D03*
X1028394Y771349D03*
Y791617D03*
X1112677Y402838D03*
Y423106D03*
X1121600Y1201266D03*
Y1221534D03*
G54D80*
X1047000Y1425700D03*
X1049000Y1431300D03*
X1045000D03*
G54D35*
X94000Y170300D03*
Y162700D03*
Y622800D03*
Y615200D03*
Y1075800D03*
Y1068200D03*
X218500Y170300D03*
Y162700D03*
Y622800D03*
Y615200D03*
Y1075800D03*
Y1068200D03*
X342500Y170300D03*
Y162700D03*
Y622800D03*
Y615200D03*
Y1075800D03*
Y1068200D03*
X467000Y170300D03*
Y162700D03*
Y622800D03*
Y615200D03*
Y1075800D03*
Y1068200D03*
X591000Y170300D03*
Y162700D03*
Y622800D03*
Y615200D03*
Y1075800D03*
Y1068200D03*
X715300Y170300D03*
Y162700D03*
Y622800D03*
Y615200D03*
Y1075800D03*
Y1068200D03*
X1007618Y1465065D03*
Y1472665D03*
X1305000Y173200D03*
Y180800D03*
X1313000Y173200D03*
Y180800D03*
X1305000Y626200D03*
Y633800D03*
X1313000Y626200D03*
Y633800D03*
X1305000Y1078700D03*
Y1086300D03*
X1313000Y1078700D03*
Y1086300D03*
X1429000Y173200D03*
Y180800D03*
X1437000Y173200D03*
Y180800D03*
X1429000Y626200D03*
Y633800D03*
X1437000Y626200D03*
Y633800D03*
X1429000Y1078700D03*
Y1086300D03*
X1437000Y1078700D03*
Y1086300D03*
X1553500Y173200D03*
Y180800D03*
X1561500Y173200D03*
Y180800D03*
X1553500Y626200D03*
Y633800D03*
X1561500Y626200D03*
Y633800D03*
X1553500Y1078700D03*
Y1086300D03*
X1561500Y1078700D03*
Y1086300D03*
X1677500Y173200D03*
Y180800D03*
X1685500Y173200D03*
Y180800D03*
X1677500Y626200D03*
Y633800D03*
X1685500Y626200D03*
Y633800D03*
X1677500Y1078700D03*
Y1086300D03*
X1685500Y1078700D03*
Y1086300D03*
X1801500Y173200D03*
Y180800D03*
X1809500Y173200D03*
Y180800D03*
X1801500Y626200D03*
Y633800D03*
X1809500Y626200D03*
Y633800D03*
X1801500Y1078700D03*
Y1086300D03*
X1809500Y1078700D03*
Y1086300D03*
X1886000Y169800D03*
Y162200D03*
X1885800Y622800D03*
Y615200D03*
X1885963Y1075886D03*
Y1068286D03*
G54D53*
X111174Y1474560D03*
Y1472000D03*
Y1469440D03*
X118574D03*
Y1472000D03*
Y1474560D03*
X203300Y68060D03*
Y65500D03*
Y62940D03*
X210700D03*
Y65500D03*
Y68060D03*
X450300D03*
Y65500D03*
Y62940D03*
X457700D03*
Y65500D03*
Y68060D03*
X700300D03*
Y65500D03*
Y62940D03*
X707700D03*
Y65500D03*
Y68060D03*
X735932Y1459794D03*
Y1457234D03*
Y1454674D03*
X743332D03*
Y1457234D03*
Y1459794D03*
X1299800Y53060D03*
Y50500D03*
Y47940D03*
X1307200D03*
Y50500D03*
Y53060D03*
X1303800Y519560D03*
Y517000D03*
Y514440D03*
X1311200D03*
Y517000D03*
Y519560D03*
X1303800Y972060D03*
Y969500D03*
Y966940D03*
X1311200D03*
Y969500D03*
Y972060D03*
X1257374Y1478960D03*
Y1476400D03*
Y1473840D03*
X1264774D03*
Y1476400D03*
Y1478960D03*
X1427800Y66560D03*
Y64000D03*
Y61440D03*
X1435200D03*
Y64000D03*
Y66560D03*
X1427800Y519560D03*
Y517000D03*
Y514440D03*
X1435200D03*
Y517000D03*
Y519560D03*
X1427800Y972060D03*
Y969500D03*
Y966940D03*
X1435200D03*
Y969500D03*
Y972060D03*
X1549300Y53060D03*
Y50500D03*
Y47940D03*
X1556700D03*
Y50500D03*
Y53060D03*
X1552300Y519560D03*
Y517000D03*
Y514440D03*
X1559700D03*
Y517000D03*
Y519560D03*
X1552300Y972060D03*
Y969500D03*
Y966940D03*
X1559700D03*
Y969500D03*
Y972060D03*
X1676300Y66560D03*
Y64000D03*
Y61440D03*
X1683700D03*
Y64000D03*
Y66560D03*
X1676300Y519560D03*
Y517000D03*
Y514440D03*
X1683700D03*
Y517000D03*
Y519560D03*
X1676300Y972060D03*
Y969500D03*
Y966940D03*
X1683700D03*
Y969500D03*
Y972060D03*
X1808600Y75260D03*
Y72700D03*
Y70140D03*
X1816000D03*
Y72700D03*
Y75260D03*
X1800300Y519560D03*
Y517000D03*
Y514440D03*
X1807700D03*
Y517000D03*
Y519560D03*
X1800300Y972060D03*
Y969500D03*
Y966940D03*
X1807700D03*
Y969500D03*
Y972060D03*
X1866700Y516440D03*
Y519000D03*
Y521560D03*
X1859300D03*
Y519000D03*
Y516440D03*
X1866700Y969440D03*
Y972000D03*
Y974560D03*
X1859300D03*
Y972000D03*
Y969440D03*
G54D71*
X859590Y650110D03*
Y652670D03*
Y655230D03*
Y657790D03*
Y660350D03*
Y662910D03*
Y665470D03*
X837390D03*
Y662910D03*
Y660350D03*
Y657790D03*
Y655230D03*
Y652670D03*
Y650110D03*
X833200Y760280D03*
Y757720D03*
Y755160D03*
Y752600D03*
Y750040D03*
Y747480D03*
Y744920D03*
X855400D03*
Y747480D03*
Y750040D03*
Y752600D03*
Y755160D03*
Y757720D03*
Y760280D03*
X859590Y668030D03*
Y670590D03*
Y673150D03*
Y675710D03*
Y678270D03*
X837390D03*
Y675710D03*
Y673150D03*
Y670590D03*
Y668030D03*
X838400Y856920D03*
X860600D03*
X833200Y773080D03*
Y770520D03*
Y767960D03*
Y765400D03*
Y762840D03*
X855400D03*
Y765400D03*
Y767960D03*
Y770520D03*
Y773080D03*
X861100Y809920D03*
Y812480D03*
Y815040D03*
Y817600D03*
Y820160D03*
Y822720D03*
Y825280D03*
Y827840D03*
Y830400D03*
Y832960D03*
Y835520D03*
Y838080D03*
X838900D03*
Y835520D03*
Y832960D03*
Y830400D03*
Y827840D03*
Y825280D03*
Y822720D03*
Y820160D03*
Y817600D03*
Y815040D03*
Y812480D03*
Y809920D03*
X838400Y885080D03*
Y882520D03*
Y879960D03*
Y877400D03*
Y874840D03*
Y872280D03*
Y869720D03*
Y867160D03*
Y864600D03*
Y862040D03*
Y859480D03*
X860600D03*
Y862040D03*
Y864600D03*
Y867160D03*
Y869720D03*
Y872280D03*
Y874840D03*
Y877400D03*
Y879960D03*
Y882520D03*
Y885080D03*
X947600Y769720D03*
Y772280D03*
Y774840D03*
Y777400D03*
Y779960D03*
Y782520D03*
Y785080D03*
Y787640D03*
Y790200D03*
Y792760D03*
Y795320D03*
Y797880D03*
X925400D03*
Y795320D03*
Y792760D03*
Y790200D03*
Y787640D03*
Y785080D03*
Y782520D03*
Y779960D03*
Y777400D03*
Y774840D03*
Y772280D03*
Y769720D03*
X898400Y1195980D03*
Y1198540D03*
Y1201100D03*
Y1203660D03*
Y1206220D03*
Y1208780D03*
Y1211340D03*
Y1213900D03*
Y1216460D03*
Y1219020D03*
X920600D03*
Y1216460D03*
Y1213900D03*
Y1211340D03*
Y1208780D03*
Y1206220D03*
Y1203660D03*
Y1201100D03*
Y1198540D03*
Y1195980D03*
X1116100Y1307375D03*
Y1304820D03*
Y1302260D03*
Y1299700D03*
Y1297140D03*
Y1294580D03*
Y1292025D03*
X1093900D03*
Y1294580D03*
Y1297140D03*
Y1299700D03*
Y1302260D03*
Y1304820D03*
Y1307375D03*
X1200912Y1399993D03*
Y1397433D03*
Y1394873D03*
Y1392313D03*
Y1389753D03*
Y1387193D03*
Y1384633D03*
Y1382073D03*
Y1379513D03*
Y1376953D03*
X1178712D03*
Y1379513D03*
Y1382073D03*
Y1384633D03*
Y1387193D03*
Y1389753D03*
Y1392313D03*
Y1394873D03*
Y1397433D03*
Y1399993D03*
G54D26*
X56700Y100500D03*
Y553000D03*
Y1006000D03*
X195200Y82500D03*
X180700Y553000D03*
X137200Y579000D03*
X107656Y878062D03*
X137200Y1032000D03*
X181200Y1006000D03*
X205483Y440326D03*
X261200Y579000D03*
X260900Y1032000D03*
X223355Y1434029D03*
X305200Y100500D03*
Y553000D03*
X385700Y579000D03*
X305200Y1006000D03*
X385700Y1032000D03*
X429200Y553000D03*
Y1006000D03*
X553700Y100500D03*
Y553000D03*
X509700Y579000D03*
Y1032000D03*
X553700Y1006000D03*
X634200Y579000D03*
Y1032000D03*
X692200Y82500D03*
X748200Y126500D03*
X677700Y553000D03*
Y1006000D03*
X749500Y1032000D03*
X692200Y1476000D03*
X710700Y1449700D03*
X837190Y645690D03*
X834900Y804500D03*
X867000Y774500D03*
X927700Y763820D03*
X867700Y887500D03*
X873400Y1188400D03*
X896500Y1191700D03*
X978081Y559671D03*
X976647Y533383D03*
X1008041Y895045D03*
X1018333Y892965D03*
X964500Y1193500D03*
X1330700Y113500D03*
X1331700Y566500D03*
Y1019000D03*
X1432200Y81000D03*
X1370429Y1434045D03*
X1455700Y113500D03*
Y566500D03*
Y1019000D03*
X1601100Y133000D03*
X1580200Y566500D03*
Y1019000D03*
X1679600Y81000D03*
X1704200Y113500D03*
Y566500D03*
Y1019000D03*
X1748252Y443744D03*
X1750574Y1434109D03*
X1878200Y81500D03*
X1862700Y82000D03*
X1863900Y42100D03*
X1827200Y113500D03*
X1828200Y566500D03*
X1876100Y534600D03*
X1848200Y553000D03*
X1822656Y878062D03*
X1828200Y1019000D03*
X1848200Y1006000D03*
G54D17*
X60000Y69800D03*
Y522300D03*
X81700Y901880D03*
X77563Y901825D03*
X60000Y975300D03*
X131600Y122700D03*
X179527Y464144D03*
X175390Y464089D03*
X184000Y522300D03*
X184500Y975300D03*
X138974Y1425700D03*
X149374Y1453800D03*
Y1435300D03*
X207000Y73800D03*
X217000Y41800D03*
X254900Y122900D03*
X308500Y69800D03*
X379500Y122900D03*
X308500Y522300D03*
Y975300D03*
X454000Y77200D03*
X465500Y41800D03*
X432500Y522300D03*
Y975300D03*
X557000Y69800D03*
X503900Y122800D03*
X557000Y522300D03*
Y975300D03*
X502999Y1448232D03*
X628000Y122800D03*
X583550Y512850D03*
X655795Y1426219D03*
X628500Y1461300D03*
X704000Y73800D03*
X714000Y41800D03*
X707800Y513500D03*
X681000Y522300D03*
X752200Y575600D03*
X681000Y975300D03*
X676500Y1476300D03*
X841939Y386415D03*
X846939D03*
X822470Y924230D03*
Y974230D03*
X830470D03*
X839970Y966470D03*
X955000Y544400D03*
X952100Y516600D03*
X922100Y757300D03*
X948500Y845800D03*
X953000D03*
X911080Y860670D03*
X918380Y915714D03*
X914260Y915670D03*
X951500Y1226300D03*
X868900Y1184800D03*
X888000Y1193900D03*
X986200Y544300D03*
X983300Y518600D03*
X966093Y845800D03*
X993942Y876100D03*
X976242Y877800D03*
X980442Y876100D03*
X1000500Y907300D03*
X1005500D03*
X959500Y1226300D03*
X963238Y1414118D03*
X998325Y1464234D03*
X1013618Y1464165D03*
X1043606Y1444949D03*
X975438Y1450208D03*
X1122112Y1366573D03*
X1134112D03*
X1114112D03*
X1118112D03*
X1138112D03*
X1203394Y1340083D03*
X1222100D03*
X1236600D03*
X1232100D03*
X1217100D03*
X1183894D03*
X1188894D03*
X1198894D03*
X1203487Y1421241D03*
X1308000Y38300D03*
X1318000D03*
X1317800Y50600D03*
X1311700Y65700D03*
X1313700Y50600D03*
X1262600Y122900D03*
X1312000Y504800D03*
X1322000D03*
X1326500Y517300D03*
X1322000D03*
X1262600Y575600D03*
X1262400Y1028300D03*
X1312000Y957300D03*
X1322000D03*
X1326500Y969800D03*
X1322000D03*
X1296374Y1453800D03*
Y1435300D03*
X1436000Y51800D03*
X1387200Y122900D03*
X1436000Y504800D03*
X1386400Y575600D03*
X1387000Y1028400D03*
X1436000Y957300D03*
X1446000Y51800D03*
X1450500Y64300D03*
X1446000D03*
X1511400Y122900D03*
X1446000Y504800D03*
X1450500Y517300D03*
X1446000D03*
X1511200Y575600D03*
X1446000Y957300D03*
X1450500Y969800D03*
X1446000D03*
X1511400Y1028400D03*
X1557500Y38300D03*
X1567500D03*
X1572000Y50800D03*
X1563500Y65800D03*
X1567500Y50800D03*
X1560500Y504800D03*
X1570500D03*
X1575000Y517300D03*
X1570500D03*
X1560500Y957300D03*
X1570500D03*
X1575000Y969800D03*
X1570500D03*
X1684500Y51800D03*
X1694500D03*
X1699000Y64300D03*
X1694500D03*
X1635300Y122900D03*
X1722296Y467562D03*
X1718159Y467507D03*
X1684500Y504800D03*
X1694500D03*
X1699000Y517300D03*
X1694500D03*
X1634200Y575600D03*
X1635100Y1028400D03*
X1684500Y957300D03*
X1694500D03*
X1699000Y969800D03*
X1694500D03*
X1676626Y1453800D03*
Y1435300D03*
X1759600Y122900D03*
X1808500Y504800D03*
X1792563Y901825D03*
X1796700Y901880D03*
X1759300Y1028400D03*
X1808500Y957300D03*
X1884600Y42300D03*
X1862300Y26600D03*
X1818500Y504800D03*
X1823000Y517300D03*
X1818500D03*
X1853000Y507300D03*
X1848500D03*
X1843000Y537800D03*
X1818500Y957300D03*
X1823000Y969800D03*
X1818500D03*
X1875800Y984800D03*
X1853000Y960300D03*
X1848500D03*
X1843000Y990800D03*
G54D44*
X150500Y29300D03*
X143300Y594500D03*
Y1047500D03*
X144674Y1457000D03*
X267300Y594500D03*
X267000Y1047500D03*
X228174Y1430000D03*
X391800Y594500D03*
Y1047500D03*
X515800Y594500D03*
Y1047500D03*
X510300Y1465500D03*
X640300Y594500D03*
Y1047500D03*
X842290Y641690D03*
X840000Y800500D03*
X862658Y1392892D03*
X932800Y759320D03*
X872300Y892000D03*
X934300Y880000D03*
X984141Y563811D03*
X1010200Y1129300D03*
X1050500Y1417000D03*
X1043350Y1480314D03*
X1291674Y1457000D03*
X1375174Y1430000D03*
X1671926Y1457000D03*
X1817300Y28900D03*
X1755426Y1430000D03*
G54D62*
X627499Y1306804D03*
X659901D03*
Y1398896D03*
X627499D03*
X948099Y1340696D03*
X980501D03*
G54D18*
X72500Y63800D03*
Y516300D03*
Y969300D03*
X102263Y912325D03*
X162374Y1428000D03*
X180374Y1416800D03*
X162274Y1419400D03*
X180374Y1409150D03*
X139374Y1478300D03*
X105474Y1473285D03*
X215500Y73800D03*
X220000D03*
X202800Y37500D03*
X200090Y474589D03*
X196500Y516300D03*
X197000Y969300D03*
X321000Y63800D03*
Y516300D03*
Y969300D03*
X464000Y73800D03*
X468500D03*
X444400Y35800D03*
X435100Y118900D03*
X445000Y516300D03*
Y969300D03*
X569500Y63800D03*
Y516300D03*
Y969300D03*
X500000Y1465300D03*
X672000Y1422300D03*
X655795Y1436719D03*
X653000Y1481300D03*
X712500Y73800D03*
X717000D03*
X699600Y37400D03*
X693500Y516300D03*
Y969300D03*
X689000Y1422300D03*
X681000D03*
X703500Y1429300D03*
X680500Y1476300D03*
X730232Y1461319D03*
X752832Y1458319D03*
X860298Y410392D03*
X862766Y421192D03*
X850947Y410392D03*
X830470Y924230D03*
X826470D03*
X818470D03*
X826470Y974230D03*
X839970D03*
X834470D03*
X872137Y421192D03*
X950639Y547041D03*
X947587Y520682D03*
X871240Y635740D03*
X868500Y799600D03*
X957500Y845800D03*
X944000D03*
X935000D03*
X939500D03*
X927260Y915670D03*
X915580Y860670D03*
X922760Y915670D03*
X909760D03*
X924670Y860640D03*
X920170D03*
X955500Y1226300D03*
X947500D03*
X943500D03*
X869937Y1386929D03*
X944016Y1445572D03*
X991129Y547701D03*
X987333Y523068D03*
X962000Y845800D03*
X977570Y831728D03*
X973070D03*
X983070Y829790D03*
X1005450Y842060D03*
X1000950D03*
X1029600Y853600D03*
X985542Y876100D03*
X989742D03*
X972042Y877800D03*
X1030515Y883281D03*
X1033315Y890881D03*
X1039500Y883300D03*
X1048000Y890300D03*
X967500Y1226300D03*
X963500D03*
X1010943Y1417199D03*
X979443Y1411199D03*
X988443Y1410199D03*
X996443D03*
X963238Y1424618D03*
X1017618Y1464165D03*
X994271Y1464217D03*
X1021618Y1464165D03*
X1038303Y1444949D03*
X1040663Y1464441D03*
X1115825Y618543D03*
X1055500Y890300D03*
X1060118Y1381389D03*
X1126112Y1366573D03*
X1130112D03*
X1223730Y1289083D03*
X1235600D03*
X1230600D03*
X1190524D03*
X1197394D03*
X1202394D03*
X1241600Y1340083D03*
X1227100D03*
X1208394D03*
X1193894D03*
X1303500Y38300D03*
X1307500Y504800D03*
Y957300D03*
X1319500Y1416800D03*
Y1409150D03*
X1251874Y1480985D03*
X1431500Y51800D03*
Y504800D03*
Y957300D03*
X1553000Y38300D03*
X1556000Y504800D03*
Y957300D03*
X1680000Y51800D03*
Y504800D03*
Y957300D03*
X1707626Y1416800D03*
Y1409150D03*
X1652510Y1453300D03*
X1799100Y75100D03*
X1808500Y61000D03*
X1803400Y50400D03*
X1808300Y50500D03*
X1804000Y504800D03*
X1742859Y478007D03*
X1817263Y912325D03*
X1804000Y957300D03*
X1807676Y1478360D03*
X1880500Y42300D03*
X1872900D03*
X1874900Y21800D03*
X1863000Y507300D03*
Y960300D03*
G54D63*
X627499Y1290524D03*
X659901D03*
Y1415176D03*
X627499D03*
X948099Y1356976D03*
X980501D03*
G54D72*
X859113Y1290032D03*
Y1301000D03*
X871556Y1290030D03*
Y1300998D03*
X884056Y1290030D03*
Y1300998D03*
X901435Y1396353D03*
Y1385385D03*
X913935Y1396353D03*
Y1385385D03*
X888776Y1396385D03*
Y1385417D03*
X1023823Y379318D03*
Y368350D03*
G54D36*
X72049Y260355D03*
X68109D03*
X72049Y254605D03*
X68109D03*
X72049Y713111D03*
X68109D03*
X72049Y707361D03*
X68109D03*
X192321Y260355D03*
Y254605D03*
Y713111D03*
Y707361D03*
X196261Y260355D03*
Y254605D03*
Y713111D03*
Y707361D03*
X320474Y260355D03*
X316534D03*
X320474Y254605D03*
X316534D03*
X320474Y713111D03*
X316534D03*
X320474Y707361D03*
X316534D03*
X444687Y260355D03*
X440747D03*
X444687Y254605D03*
X440747D03*
X444687Y713111D03*
X440747D03*
X444687Y707361D03*
X440747D03*
X568899Y260355D03*
X564959D03*
X568899Y254605D03*
X564959D03*
X568899Y713111D03*
X564959D03*
X568899Y707361D03*
X564959D03*
X693112Y260355D03*
X689172D03*
X693112Y254605D03*
X689172D03*
X693112Y713111D03*
X689172D03*
X693112Y707361D03*
X689172D03*
X1242718Y260355D03*
X1238778D03*
X1242718Y254605D03*
X1238778D03*
X1242718Y713111D03*
X1238778D03*
X1242718Y707361D03*
X1238778D03*
X1366931Y260355D03*
X1362991D03*
X1366931Y254605D03*
X1362991D03*
X1366931Y713111D03*
X1362991D03*
X1366931Y707361D03*
X1362991D03*
X1491143Y260355D03*
X1487203D03*
X1491143Y254605D03*
X1487203D03*
X1491143Y713111D03*
X1487203D03*
X1491143Y707361D03*
X1487203D03*
X1615356Y260355D03*
X1611416D03*
X1615356Y254605D03*
X1611416D03*
X1615356Y713111D03*
X1611416D03*
X1615356Y707361D03*
X1611416D03*
X1739568Y260355D03*
X1735628D03*
X1739568Y254605D03*
X1735628D03*
X1739568Y713111D03*
X1735628D03*
X1739568Y707361D03*
X1735628D03*
X1863781Y260355D03*
X1859841D03*
X1863781Y254605D03*
X1859841D03*
X1863781Y713111D03*
X1859841D03*
X1863781Y707361D03*
X1859841D03*
G54D54*
X153524Y1464000D03*
X140224D03*
X153524Y1445500D03*
X140224D03*
X1300524Y1464000D03*
X1287224D03*
X1300524Y1445500D03*
X1287224D03*
X1680776Y1464000D03*
X1667476D03*
X1680776Y1445500D03*
X1667476D03*
G54D81*
X1104760Y1334815D03*
X1112240D03*
Y1343815D03*
X1108500D03*
X1104760D03*
G54D45*
X144900Y29300D03*
X137700Y594500D03*
Y1047500D03*
X139074Y1457000D03*
X261700Y594500D03*
X261400Y1047500D03*
X222574Y1430000D03*
X386200Y594500D03*
Y1047500D03*
X510200Y594500D03*
Y1047500D03*
X504700Y1465500D03*
X634700Y594500D03*
Y1047500D03*
X836690Y641690D03*
X834400Y800500D03*
X857058Y1392892D03*
X927200Y759320D03*
X866700Y892000D03*
X928700Y880000D03*
X978541Y563811D03*
X1004600Y1129300D03*
X1044900Y1417000D03*
X1037750Y1480314D03*
X1286074Y1457000D03*
X1369574Y1430000D03*
X1666326Y1457000D03*
X1811700Y28900D03*
X1749826Y1430000D03*
G54D27*
X60300Y100500D03*
Y553000D03*
Y1006000D03*
X184300Y553000D03*
X140800Y579000D03*
X111256Y878062D03*
X140800Y1032000D03*
X184800Y1006000D03*
X198800Y82500D03*
X209083Y440326D03*
X264800Y579000D03*
X264500Y1032000D03*
X226955Y1434029D03*
X308800Y100500D03*
Y553000D03*
Y1006000D03*
X432800Y553000D03*
X389300Y579000D03*
Y1032000D03*
X432800Y1006000D03*
X557300Y100500D03*
Y553000D03*
X513300Y579000D03*
Y1032000D03*
X557300Y1006000D03*
X637800Y579000D03*
Y1032000D03*
X695800Y82500D03*
X751800Y126500D03*
X681300Y553000D03*
Y1006000D03*
X753100Y1032000D03*
X695800Y1476000D03*
X714300Y1449700D03*
X840790Y645690D03*
X838500Y804500D03*
X870600Y774500D03*
X931300Y763820D03*
X871300Y887500D03*
X877000Y1188400D03*
X900100Y1191700D03*
X981681Y559671D03*
X980247Y533383D03*
X1011641Y895045D03*
X1021933Y892965D03*
X968100Y1193500D03*
X1334300Y113500D03*
X1335300Y566500D03*
Y1019000D03*
X1435800Y81000D03*
X1374029Y1434045D03*
X1459300Y113500D03*
Y566500D03*
Y1019000D03*
X1604700Y133000D03*
X1583800Y566500D03*
Y1019000D03*
X1683200Y81000D03*
X1707800Y113500D03*
Y566500D03*
Y1019000D03*
X1751852Y443744D03*
X1754174Y1434109D03*
X1881800Y81500D03*
X1866300Y82000D03*
X1867500Y42100D03*
X1830800Y113500D03*
X1831800Y566500D03*
X1879700Y534600D03*
X1851800Y553000D03*
X1826256Y878062D03*
X1831800Y1019000D03*
X1851800Y1006000D03*
G54D19*
X72500Y67200D03*
Y519700D03*
Y972700D03*
X102263Y915725D03*
X180374Y1420200D03*
X162274Y1422800D03*
X180374Y1412550D03*
X139374Y1481700D03*
X162374Y1431400D03*
X105474Y1476685D03*
X215500Y77200D03*
X220000D03*
X202800Y40900D03*
X196500Y519700D03*
X200090Y477989D03*
X197000Y972700D03*
X321000Y67200D03*
Y519700D03*
Y972700D03*
X464000Y77200D03*
X468500D03*
X444400Y39200D03*
X435100Y122300D03*
X445000Y519700D03*
Y972700D03*
X569500Y67200D03*
Y519700D03*
Y972700D03*
X500000Y1468700D03*
X672000Y1425700D03*
X655795Y1440119D03*
X653000Y1484700D03*
X712500Y77200D03*
X717000D03*
X699600Y40800D03*
X693500Y519700D03*
Y972700D03*
X689000Y1425700D03*
X681000D03*
X680500Y1479700D03*
X703500Y1432700D03*
X730232Y1464719D03*
X752832Y1461719D03*
X860298Y413792D03*
X862766Y424592D03*
X850947Y413792D03*
X830470Y927630D03*
X826470D03*
X818470D03*
X826470Y977630D03*
X839970D03*
X834470D03*
X872137Y424592D03*
X950639Y550441D03*
X947587Y524082D03*
X871240Y639140D03*
X868500Y803000D03*
X957500Y849200D03*
X944000D03*
X935000D03*
X939500D03*
X927260Y919070D03*
X915580Y864070D03*
X922760Y919070D03*
X909760D03*
X924670Y864040D03*
X920170D03*
X955500Y1229700D03*
X947500D03*
X943500D03*
X869937Y1390329D03*
X944016Y1448972D03*
X991129Y551101D03*
X987333Y526468D03*
X962000Y849200D03*
X977570Y835128D03*
X973070D03*
X983070Y833190D03*
X1005450Y845460D03*
X1000950D03*
X1029600Y857000D03*
X985542Y879500D03*
X989742D03*
X972042Y881200D03*
X1030515Y886681D03*
X1033315Y894281D03*
X1039500Y886700D03*
X1048000Y893700D03*
X967500Y1229700D03*
X963500D03*
X1010943Y1420599D03*
X979443Y1414599D03*
X988443Y1413599D03*
X996443D03*
X963238Y1428018D03*
X1017618Y1467565D03*
X994271Y1467617D03*
X1021618Y1467565D03*
X1038303Y1448349D03*
X1040663Y1467841D03*
X1115825Y621943D03*
X1055500Y893700D03*
X1060118Y1384789D03*
X1126112Y1369973D03*
X1130112D03*
X1223730Y1292483D03*
X1235600D03*
X1230600D03*
X1190524D03*
X1197394D03*
X1202394D03*
X1241600Y1343483D03*
X1227100D03*
X1208394D03*
X1193894D03*
X1303500Y41700D03*
X1307500Y508200D03*
Y960700D03*
X1319500Y1420200D03*
Y1412550D03*
X1251874Y1484385D03*
X1431500Y55200D03*
Y508200D03*
Y960700D03*
X1553000Y41700D03*
X1556000Y508200D03*
Y960700D03*
X1680000Y55200D03*
Y508200D03*
Y960700D03*
X1707626Y1420200D03*
Y1412550D03*
X1652510Y1456700D03*
X1799100Y78500D03*
X1808500Y64400D03*
X1803400Y53800D03*
X1808300Y53900D03*
X1804000Y508200D03*
X1742859Y481407D03*
X1817263Y915725D03*
X1804000Y960700D03*
X1807676Y1481760D03*
X1880500Y45700D03*
X1872900D03*
X1874900Y25200D03*
X1863000Y510700D03*
Y963700D03*
G54D28*
X76700Y133000D03*
X76600Y585500D03*
X94463Y903525D03*
X76500Y1038400D03*
X192290Y465789D03*
X139074Y1438500D03*
X201000Y133000D03*
Y585500D03*
X201100Y1038500D03*
X325300Y133000D03*
Y585500D03*
X325100Y1038500D03*
X449300Y133000D03*
X449600Y585500D03*
X449100Y1038500D03*
X573800Y133000D03*
X573700Y585500D03*
Y1038500D03*
X662200Y1448500D03*
X698000Y133000D03*
Y585500D03*
X697900Y1038500D03*
X861800Y779100D03*
X939200Y894000D03*
X966318Y534117D03*
X1010150Y842360D03*
X1026934Y1391632D03*
X969643Y1436399D03*
X1107200Y1327500D03*
X1109200Y1354000D03*
X1286074Y1438500D03*
X1666326D03*
X1735059Y469207D03*
X1757200Y595000D03*
X1809463Y903525D03*
X1872498Y68922D03*
X1868600Y132500D03*
X1868700Y585500D03*
X1868400Y1038500D03*
G54D64*
X666250Y1485000D03*
X658750Y1481125D03*
Y1488875D03*
X954750Y908000D03*
X947250Y911875D03*
Y904125D03*
X957266Y1449272D03*
X949766Y1445397D03*
Y1453147D03*
X1024507Y929750D03*
X1017007Y933625D03*
Y925875D03*
G54D55*
X113314Y1452450D03*
X115874D03*
X118434D03*
Y1458950D03*
X113314D03*
X741572Y1438184D03*
X744132D03*
X746692D03*
Y1444684D03*
X741572D03*
X1030003Y1444649D03*
X1027443D03*
X1024883D03*
Y1438149D03*
X1030003D03*
X1259614Y1457550D03*
X1262174D03*
X1264734D03*
Y1464050D03*
X1259614D03*
X1796666Y1456950D03*
X1799226D03*
X1801786D03*
Y1463450D03*
X1796666D03*
G54D73*
X809631Y1320085D03*
Y1315085D03*
Y1310085D03*
Y1305085D03*
X810101Y1362591D03*
Y1357591D03*
Y1352591D03*
Y1347591D03*
X809880Y1400259D03*
Y1395259D03*
Y1390259D03*
Y1385259D03*
X1028118Y1327489D03*
Y1322489D03*
Y1317489D03*
Y1312489D03*
Y1383089D03*
Y1378089D03*
Y1373089D03*
Y1368089D03*
Y1355289D03*
Y1350289D03*
Y1345289D03*
Y1340289D03*
G54D37*
X79567Y388546D03*
X84567D03*
X73500Y840700D03*
X68500D03*
X95263Y880325D03*
X193090Y442589D03*
X191000Y840700D03*
X196000D03*
X213200Y388200D03*
X218200D03*
X315500D03*
X320500D03*
X315500Y840700D03*
X320500D03*
X440000Y388200D03*
X445000D03*
Y840700D03*
X440000D03*
X564000Y388200D03*
X569000D03*
X564000Y840700D03*
X569000D03*
X651295Y1435619D03*
X680500Y388200D03*
X685500D03*
X680500Y840700D03*
X685500D03*
X676500Y1423700D03*
X958738Y1423518D03*
X998000Y1114200D03*
X983943Y1411599D03*
X1040127Y1426700D03*
X1243500Y383700D03*
X1238462Y836388D03*
X1243462D03*
X1248500Y383700D03*
X1362500Y387700D03*
X1367500D03*
X1377100Y573400D03*
X1362500Y841200D03*
X1367500D03*
X1376900Y1026000D03*
X1487000Y387700D03*
X1492000D03*
X1500800Y573000D03*
X1487000Y840700D03*
X1492000D03*
X1500700Y1026000D03*
X1611000Y387700D03*
X1616000D03*
X1625500Y573200D03*
X1611000Y840700D03*
X1616000D03*
X1625400Y1026100D03*
X1735859Y446007D03*
X1735000Y387700D03*
X1740000D03*
X1735000Y840700D03*
X1740000D03*
X1810263Y880325D03*
X1749300Y1026100D03*
X1832100Y388500D03*
X1827100D03*
X1876100Y515400D03*
X1859500Y840700D03*
X1864500D03*
X1867500Y982400D03*
G54D82*
X1100000Y1493110D03*
Y1483268D03*
G54D46*
X149300Y37300D03*
X136866Y156319D03*
Y609075D03*
X116263Y911525D03*
X136866Y1061831D03*
X261078Y156319D03*
X214090Y473789D03*
X261078Y609075D03*
Y1061831D03*
X385291Y156319D03*
Y609075D03*
Y1061831D03*
X509503Y156319D03*
Y609075D03*
Y1061831D03*
X633716Y156319D03*
Y609075D03*
Y1061831D03*
X708200Y148900D03*
X757929Y609075D03*
Y1061831D03*
X1020061Y847967D03*
X1256756Y156319D03*
Y609075D03*
Y1061831D03*
X1380969Y156319D03*
Y609075D03*
Y1061831D03*
X1505181Y156319D03*
Y609075D03*
Y1061831D03*
X1629394Y156319D03*
Y609075D03*
Y1061831D03*
X1812800Y38200D03*
X1753606Y156319D03*
X1756859Y477207D03*
X1753606Y609075D03*
Y1061831D03*
X1878100Y149600D03*
X1878200Y602900D03*
X1831263Y911525D03*
X1878300Y1056100D03*
G54D65*
X679950Y1446610D03*
Y1460390D03*
X700050D03*
Y1446610D03*
X987393Y1434509D03*
Y1448289D03*
X1007493D03*
Y1434509D03*
G54D74*
X959913Y519617D03*
Y522177D03*
Y524737D03*
Y527297D03*
X978571Y553411D03*
Y550851D03*
Y548291D03*
Y545731D03*
X962271D03*
Y548291D03*
Y550851D03*
Y553411D03*
X976213Y527297D03*
Y524737D03*
Y522177D03*
Y519617D03*
G54D47*
X137501Y24706D03*
X134941D03*
X132381D03*
X129821D03*
Y40886D03*
X132381D03*
X134941D03*
X137501D03*
X799390Y940330D03*
X801950D03*
X804510D03*
X807070D03*
X809630D03*
X812190D03*
X814750D03*
X817310D03*
X819870D03*
X822430D03*
X824990D03*
X827550D03*
Y962530D03*
X824990D03*
X822430D03*
X819870D03*
X817310D03*
X814750D03*
X812190D03*
X809630D03*
X807070D03*
X804510D03*
X801950D03*
X799390D03*
X917620Y902564D03*
X915060D03*
X912500D03*
X909940D03*
X907380D03*
X904820D03*
X902260D03*
X899700D03*
X897140D03*
X894580D03*
X892020D03*
X889460D03*
Y880364D03*
X892020D03*
X894580D03*
X897140D03*
X899700D03*
X902260D03*
X904820D03*
X907380D03*
X909940D03*
X912500D03*
X915060D03*
X917620D03*
X946310Y861030D03*
X948870D03*
X951430D03*
X953990D03*
X956550D03*
Y883230D03*
X953990D03*
X951430D03*
X948870D03*
X946310D03*
X1002940Y856130D03*
X1005500D03*
X1008060D03*
X1010620D03*
X1013180D03*
X1015740D03*
X1018300D03*
X1020860D03*
X959110Y861030D03*
X961670D03*
X964230D03*
Y883230D03*
X961670D03*
X959110D03*
X1020860Y878330D03*
X1018300D03*
X1015740D03*
X1013180D03*
X1010620D03*
X1008060D03*
X1005500D03*
X1002940D03*
X1805021Y23406D03*
X1802461D03*
X1799901D03*
X1797341D03*
Y39586D03*
X1799901D03*
X1802461D03*
X1805021D03*
G54D56*
X110639Y1486040D03*
Y1488600D03*
Y1491160D03*
X118709D03*
Y1488600D03*
Y1486040D03*
X736597Y1471974D03*
Y1474534D03*
Y1477094D03*
X744667D03*
Y1474534D03*
Y1471974D03*
X1256939Y1490840D03*
Y1493400D03*
Y1495960D03*
X1265009D03*
Y1493400D03*
Y1490840D03*
G54D38*
X79567Y394146D03*
X84567D03*
X73500Y846300D03*
X68500D03*
X95263Y885925D03*
X193090Y448189D03*
X191000Y846300D03*
X196000D03*
X213200Y393800D03*
X218200D03*
X315500D03*
X320500D03*
X315500Y846300D03*
X320500D03*
X440000Y393800D03*
X445000D03*
Y846300D03*
X440000D03*
X564000Y393800D03*
X569000D03*
X564000Y846300D03*
X569000D03*
X651295Y1441219D03*
X680500Y393800D03*
X685500D03*
X680500Y846300D03*
X685500D03*
X676500Y1429300D03*
X958738Y1429118D03*
X998000Y1119800D03*
X983943Y1417199D03*
X1040127Y1432300D03*
X1243500Y389300D03*
X1238462Y841988D03*
X1243462D03*
X1248500Y389300D03*
X1362500Y393300D03*
X1367500D03*
X1377100Y579000D03*
X1362500Y846800D03*
X1367500D03*
X1376900Y1031600D03*
X1487000Y393300D03*
X1492000D03*
X1500800Y578600D03*
X1487000Y846300D03*
X1492000D03*
X1500700Y1031600D03*
X1611000Y393300D03*
X1616000D03*
X1625500Y578800D03*
X1611000Y846300D03*
X1616000D03*
X1625400Y1031700D03*
X1735859Y451607D03*
X1735000Y393300D03*
X1740000D03*
X1735000Y846300D03*
X1740000D03*
X1810263Y885925D03*
X1749300Y1031700D03*
X1832100Y394100D03*
X1827100D03*
X1876100Y521000D03*
X1859500Y846300D03*
X1864500D03*
X1867500Y988000D03*
G54D83*
X1060729Y1493189D03*
Y1483189D03*
G54D29*
X82300Y133000D03*
X82200Y585500D03*
X100063Y903525D03*
X82100Y1038400D03*
X144674Y1438500D03*
X206600Y133000D03*
X197890Y465789D03*
X206600Y585500D03*
X206700Y1038500D03*
X330900Y133000D03*
Y585500D03*
X330700Y1038500D03*
X454900Y133000D03*
X455200Y585500D03*
X454700Y1038500D03*
X579400Y133000D03*
X579300Y585500D03*
Y1038500D03*
X667800Y1448500D03*
X703600Y133000D03*
Y585500D03*
X703500Y1038500D03*
X867400Y779100D03*
X944800Y894000D03*
X971918Y534117D03*
X1015750Y842360D03*
X1032534Y1391632D03*
X975243Y1436399D03*
X1112800Y1327500D03*
X1114800Y1354000D03*
X1291674Y1438500D03*
X1671926D03*
X1740659Y469207D03*
X1762800Y595000D03*
X1815063Y903525D03*
X1878098Y68922D03*
X1874200Y132500D03*
X1874300Y585500D03*
X1874000Y1038500D03*
G54D39*
X69567Y389096D03*
X73442Y396596D03*
X65692D03*
X57300Y841750D03*
X61175Y849250D03*
X53425D03*
X180300Y841750D03*
X184175Y849250D03*
X176425D03*
X171374Y1421750D03*
X175249Y1429250D03*
X167499D03*
X203700Y388850D03*
X207575Y396350D03*
X199825D03*
X305400Y389050D03*
X309275Y396550D03*
X301525D03*
X305400Y841750D03*
X309275Y849250D03*
X301525D03*
X429900Y388850D03*
X433775Y396350D03*
X426025D03*
X429600Y841550D03*
X433475Y849050D03*
X425725D03*
X554100Y389050D03*
X557975Y396550D03*
X550225D03*
X665100Y388850D03*
X668975Y396350D03*
X661225D03*
X593680Y842750D03*
X597555Y850250D03*
X589805D03*
X670500Y841550D03*
X666625Y849050D03*
X674375D03*
X934000Y862250D03*
X937875Y869750D03*
X930125D03*
X1016000Y910750D03*
X1019875Y918250D03*
X1012125D03*
X1028050Y1479564D03*
X1024175Y1487064D03*
X1031925D03*
X1031163Y1464391D03*
X1035038Y1471891D03*
X1027288D03*
X1227969Y841750D03*
X1231844Y849250D03*
X1224094D03*
X1209846Y1407553D03*
X1213721Y1415053D03*
X1205971D03*
X1273803Y388837D03*
X1277678Y396337D03*
X1269928D03*
X1310500Y1421750D03*
X1314375Y1429250D03*
X1306625D03*
X1352182Y388994D03*
X1356057Y396494D03*
X1348307D03*
X1352182Y841750D03*
X1356057Y849250D03*
X1348307D03*
X1476394Y388994D03*
X1480269Y396494D03*
X1472519D03*
X1476394Y841750D03*
X1480269Y849250D03*
X1472519D03*
X1600607Y388994D03*
X1604482Y396494D03*
X1596732D03*
X1600607Y841750D03*
X1604482Y849250D03*
X1596732D03*
X1720944D03*
X1698626Y1421750D03*
X1702501Y1429250D03*
X1694751D03*
X1763791Y388797D03*
X1767666Y396297D03*
X1759916D03*
X1816000Y389350D03*
X1812125Y396850D03*
X1749634Y388793D03*
X1753509Y396293D03*
X1745759D03*
X1724819Y841750D03*
X1728694Y849250D03*
X1819875Y396850D03*
X1849032Y841750D03*
X1852907Y849250D03*
X1845157D03*
G54D66*
X680250Y1448579D03*
Y1450547D03*
Y1452516D03*
Y1454484D03*
Y1456453D03*
Y1458421D03*
X699750D03*
Y1456453D03*
Y1454484D03*
Y1452516D03*
Y1450547D03*
Y1448579D03*
X987693Y1436478D03*
Y1438446D03*
Y1440415D03*
Y1442383D03*
Y1444352D03*
Y1446320D03*
X1007193D03*
Y1444352D03*
Y1442383D03*
Y1440415D03*
Y1438446D03*
Y1436478D03*
G54D84*
X1228100Y1316783D03*
X1194894D03*
G54D57*
X217500Y51200D03*
X208500D03*
X466000Y51500D03*
X457000D03*
X714500Y51300D03*
X705500D03*
X1040500Y1410500D03*
X1049500D03*
X1323500Y527000D03*
X1332500D03*
X1323500Y979500D03*
X1332500D03*
X1447500Y74000D03*
X1456500D03*
X1447500Y527000D03*
X1456500D03*
X1447500Y979500D03*
X1456500D03*
X1572000Y527000D03*
X1581000D03*
X1572000Y979500D03*
X1581000D03*
X1696000Y74000D03*
X1705000D03*
X1696000Y527000D03*
X1705000D03*
X1696000Y979500D03*
X1705000D03*
X1818900Y94400D03*
X1827900D03*
X1820000Y527000D03*
X1829000D03*
X1820000Y979500D03*
X1829000D03*
G54D48*
X127600Y126200D03*
X158474Y1422900D03*
X153374Y1457300D03*
Y1438800D03*
X250900Y126400D03*
X375500D03*
X440849Y118900D03*
X499900Y126300D03*
X624000D03*
X668000Y1425800D03*
X672500Y1479800D03*
X748200Y579100D03*
X698500Y1425800D03*
X685000D03*
X693000D03*
X735232Y1447134D03*
X990100Y833300D03*
X1026515Y886781D03*
X1000443Y1413699D03*
X992443D03*
X975443Y1414699D03*
X1005943Y1413699D03*
X971438Y1453708D03*
X1035943Y1431699D03*
X1207440Y1424654D03*
X1266600Y126400D03*
Y579100D03*
X1266400Y1031800D03*
X1300374Y1457300D03*
Y1438800D03*
X1253374Y1466700D03*
X1391200Y126400D03*
X1390400Y579100D03*
X1391000Y1031900D03*
X1515400Y126400D03*
X1515200Y579100D03*
X1515400Y1031900D03*
X1639300Y126400D03*
X1638200Y579100D03*
X1639100Y1031900D03*
X1680626Y1457300D03*
Y1438800D03*
X1763600Y126400D03*
X1763300Y1031900D03*
X1790226Y1465900D03*
X1879800Y988300D03*
G54D75*
X903125Y758850D03*
X910875D03*
X907000Y766350D03*
X874000Y1205650D03*
X870125Y1198150D03*
X877875D03*
G54D85*
X1267378Y57719D03*
X1265178D03*
X1267378Y59919D03*
X1265178D03*
X1267378Y510475D03*
X1265178D03*
X1267378Y512675D03*
X1265178D03*
X1267378Y963231D03*
X1265178D03*
X1267378Y965431D03*
X1265178D03*
X1391591Y57719D03*
X1389391D03*
X1391591Y59919D03*
X1389391D03*
X1391591Y510475D03*
X1389391D03*
X1391591Y512675D03*
X1389391D03*
X1391591Y963231D03*
X1389391D03*
X1391591Y965431D03*
X1389391D03*
X1515803Y57719D03*
X1513603D03*
X1515803Y59919D03*
X1513603D03*
X1515803Y510475D03*
X1513603D03*
X1515803Y512675D03*
X1513603D03*
X1515803Y963231D03*
X1513603D03*
X1515803Y965431D03*
X1513603D03*
X1640016Y59919D03*
X1637816D03*
X1640016Y57719D03*
X1637816D03*
X1640016Y512675D03*
X1637816D03*
X1640016Y510475D03*
X1637816D03*
X1640016Y963231D03*
X1637816D03*
X1640016Y965431D03*
X1637816D03*
X1764228Y57719D03*
X1762028D03*
X1764228Y59919D03*
X1762028D03*
X1764228Y510475D03*
X1762028D03*
X1764228Y512675D03*
X1762028D03*
X1764228Y963231D03*
X1762028D03*
X1764228Y965431D03*
X1762028D03*
X1888441Y57719D03*
X1886241D03*
X1888441Y59919D03*
X1886241D03*
X1888441Y510475D03*
X1886241D03*
X1888441Y512675D03*
X1886241D03*
X1888441Y963231D03*
X1886241D03*
X1888441Y965431D03*
X1886241D03*
G54D67*
X683110Y1463550D03*
X696890D03*
Y1443450D03*
X683110D03*
X990553Y1451449D03*
X1004333D03*
Y1431349D03*
X990553D03*
G54D49*
X127600Y122600D03*
X158474Y1419300D03*
X153374Y1453700D03*
Y1435200D03*
X250900Y122800D03*
X375500D03*
X440849Y115300D03*
X499900Y122700D03*
X624000D03*
X668000Y1422200D03*
X672500Y1476200D03*
X748200Y575500D03*
X698500Y1422200D03*
X685000D03*
X693000D03*
X735232Y1443534D03*
X990100Y829700D03*
X1026515Y883181D03*
X1000443Y1410099D03*
X992443D03*
X975443Y1411099D03*
X1005943Y1410099D03*
X1035943Y1428099D03*
X971438Y1450108D03*
X1207440Y1421054D03*
X1266600Y122800D03*
Y575500D03*
X1266400Y1028200D03*
X1300374Y1453700D03*
Y1435200D03*
X1253374Y1463100D03*
X1391200Y122800D03*
X1390400Y575500D03*
X1391000Y1028300D03*
X1515400Y122800D03*
X1515200Y575500D03*
X1515400Y1028300D03*
X1639300Y122800D03*
X1638200Y575500D03*
X1639100Y1028300D03*
X1680626Y1453700D03*
Y1435200D03*
X1763600Y122800D03*
X1763300Y1028300D03*
X1790226Y1462300D03*
X1879800Y984700D03*
G54D76*
X949000Y1202776D03*
Y1204350D03*
Y1205925D03*
Y1207500D03*
Y1209075D03*
Y1210650D03*
Y1212224D03*
X965000D03*
Y1210650D03*
Y1209075D03*
Y1207500D03*
Y1205925D03*
Y1204350D03*
Y1202776D03*
X1116612Y1384049D03*
Y1385623D03*
Y1387198D03*
Y1388773D03*
Y1390348D03*
Y1391923D03*
Y1393497D03*
X1132612D03*
Y1391923D03*
Y1390348D03*
Y1388773D03*
Y1387198D03*
Y1385623D03*
Y1384049D03*
G54D58*
X231674Y1421000D03*
X220074D03*
X1378174D03*
X1366574D03*
X1758440Y1420946D03*
X1746840D03*
G54D86*
X1328500Y554500D03*
Y549500D03*
Y544500D03*
Y539500D03*
X1308500D03*
Y544500D03*
Y549500D03*
Y554500D03*
X1328500Y1007000D03*
Y1002000D03*
Y997000D03*
Y992000D03*
X1308500D03*
Y997000D03*
Y1002000D03*
Y1007000D03*
X1432500Y86500D03*
Y91500D03*
Y96500D03*
Y101500D03*
Y539500D03*
Y544500D03*
Y549500D03*
Y554500D03*
Y992000D03*
Y997000D03*
Y1002000D03*
Y1007000D03*
X1452500Y91500D03*
Y86500D03*
Y101500D03*
Y96500D03*
Y554500D03*
Y549500D03*
Y544500D03*
Y539500D03*
Y1007000D03*
Y1002000D03*
Y997000D03*
Y992000D03*
X1570400Y126000D03*
Y131000D03*
Y136000D03*
Y141000D03*
X1590400D03*
Y136000D03*
Y131000D03*
Y126000D03*
X1577000Y554500D03*
Y549500D03*
Y544500D03*
Y539500D03*
X1557000D03*
Y544500D03*
Y549500D03*
Y554500D03*
X1577000Y1007000D03*
Y1002000D03*
Y997000D03*
Y992000D03*
X1557000D03*
Y997000D03*
Y1002000D03*
Y1007000D03*
X1701000Y91500D03*
Y86500D03*
X1681000D03*
Y91500D03*
X1701000Y101500D03*
Y96500D03*
X1681000D03*
Y101500D03*
X1701000Y554500D03*
Y549500D03*
Y544500D03*
Y539500D03*
X1681000D03*
Y544500D03*
Y549500D03*
Y554500D03*
X1701000Y1007000D03*
Y1002000D03*
Y997000D03*
Y992000D03*
X1681000D03*
Y997000D03*
Y1002000D03*
Y1007000D03*
X1805000Y539500D03*
Y544500D03*
Y549500D03*
Y554500D03*
Y992000D03*
Y997000D03*
Y1002000D03*
Y1007000D03*
X1825000Y554500D03*
Y549500D03*
Y544500D03*
Y539500D03*
Y1007000D03*
Y1002000D03*
Y997000D03*
Y992000D03*
G54D68*
X685079Y1463250D03*
X687047D03*
X689016D03*
X690984D03*
X692953D03*
X694921D03*
Y1443750D03*
X692953D03*
X690984D03*
X689016D03*
X687047D03*
X685079D03*
X992522Y1451149D03*
X994490D03*
X996459D03*
X998427D03*
X1000396D03*
X1002364D03*
Y1431649D03*
X1000396D03*
X998427D03*
X996459D03*
X994490D03*
X992522D03*
G54D77*
X957000Y1199500D03*
X955425D03*
X953850D03*
X952276D03*
Y1215500D03*
X953850D03*
X955425D03*
X957000D03*
X961724Y1199500D03*
X960150D03*
X958575D03*
Y1215500D03*
X960150D03*
X961724D03*
X1119888Y1396773D03*
X1121462D03*
X1123037D03*
X1124612D03*
X1126187D03*
X1127762D03*
X1129336D03*
Y1380773D03*
X1127762D03*
X1126187D03*
X1124612D03*
X1123037D03*
X1121462D03*
X1119888D03*
G54D59*
X418505Y1423348D03*
X390221D03*
G54D69*
X690000Y1453500D03*
X997443Y1441399D03*
G54D87*
X1813566Y1484735D03*
X1816126D03*
Y1476665D03*
X1813566D03*
X1818686Y1484735D03*
Y1476665D03*
G54D78*
X934500Y1367958D03*
Y1396242D03*
G54D88*
G01X466941Y-145664D02*
Y-225664D01*
G01D02*
X1593241D01*
G01X462941Y-129664D02*
G02I-12000J0D01*
G01X457791D02*
G02I-6850J0D01*
G01X450941Y-145664D02*
Y-113664D01*
G01X466941Y-129664D02*
X434941D01*
G01X466941Y-145664D02*
X1593241D01*
G01X466941Y-181164D02*
X1593241D01*
G01X805741Y-145664D02*
Y-225664D01*
G01X943241Y-145664D02*
Y-225664D01*
G01X1058241Y-145664D02*
Y-225664D01*
G01X1225741Y-145664D02*
Y-225664D01*
G01X1395741Y-145664D02*
Y-225664D01*
G01X1593241Y-145664D02*
Y-225664D01*
G01X1621241Y-129664D02*
G02I-12000J0D01*
G01X1616091D02*
G02I-6850J0D01*
G01X1609241Y-145664D02*
Y-113664D01*
G01X1625241Y-129664D02*
X1593241D01*
G54D79*
X1042147Y379090D03*
X1066947D03*
G54D89*
G01X489037Y-206331D02*
X489911Y-205456D01*
X490566Y-203998D01*
X491003Y-201955D01*
X490566Y-200206D01*
X489693Y-199039D01*
X488164Y-198164D01*
X482269D01*
Y-215664D01*
X489474D01*
X491003Y-214498D01*
X491876Y-212747D01*
X492313Y-210706D01*
X491876Y-208664D01*
X490566Y-206914D01*
X489037Y-206331D01*
X482269D01*
G01X501734Y-215664D02*
Y-203998D01*
G01Y-206331D02*
X502826Y-205164D01*
X503918Y-204289D01*
X505446Y-203998D01*
X506537Y-204289D01*
X507848Y-205164D01*
G01X517706Y-220914D02*
X519016Y-221497D01*
X520763Y-220914D01*
X521854Y-219748D01*
X522728Y-218289D01*
X524037Y-213623D01*
X526876Y-203998D01*
G01X519889D02*
X524037Y-213623D01*
G01X543284Y-205456D02*
X541756Y-204289D01*
X540446Y-203998D01*
X538699Y-204581D01*
X537389Y-205747D01*
X536516Y-207789D01*
X536297Y-209831D01*
X536516Y-211873D01*
X537389Y-213623D01*
X538699Y-215081D01*
X540446Y-215664D01*
X541974Y-215081D01*
X543284Y-213914D01*
G01X554016Y-207789D02*
X561003D01*
X560348Y-205747D01*
X559256Y-204581D01*
X557728Y-203998D01*
X556199Y-204289D01*
X554889Y-205164D01*
X554016Y-207206D01*
X553579Y-208956D01*
Y-210706D01*
X554016Y-212456D01*
X555108Y-214206D01*
X556418Y-215372D01*
X557946Y-215664D01*
X559474Y-215081D01*
X561003Y-213331D01*
G01X597094Y-199623D02*
X595784Y-198747D01*
X594256Y-198164D01*
X592509D01*
X590544Y-199039D01*
X589016Y-200497D01*
X587924Y-202248D01*
X587051Y-205164D01*
X586832Y-207789D01*
X587269Y-210414D01*
X587924Y-212164D01*
X589234Y-213914D01*
X590763Y-215081D01*
X592291Y-215664D01*
X593819D01*
X595348Y-215081D01*
X596658Y-214206D01*
X597750Y-213040D01*
G01X613721Y-215664D02*
Y-203998D01*
G01Y-206039D02*
X612848Y-204873D01*
X611537Y-204289D01*
X610009Y-203998D01*
X608481Y-204581D01*
X607171Y-205747D01*
X606297Y-207497D01*
X605861Y-209831D01*
X606297Y-212164D01*
X607171Y-213914D01*
X608481Y-215081D01*
X610009Y-215664D01*
X611537Y-215372D01*
X612848Y-214498D01*
X613721Y-213331D01*
G01X623579Y-215664D02*
Y-203998D01*
G01Y-206914D02*
X624453Y-205456D01*
X625763Y-204289D01*
X627509Y-203998D01*
X629037Y-204289D01*
X630348Y-205456D01*
X631003Y-207497D01*
Y-215664D01*
G01X640206Y-220914D02*
X641516Y-221497D01*
X643263Y-220914D01*
X644354Y-219748D01*
X645228Y-218289D01*
X646537Y-213623D01*
X649376Y-203998D01*
G01X642389D02*
X646537Y-213623D01*
G01X662291Y-215664D02*
X660981Y-215372D01*
X659671Y-214206D01*
X658797Y-212164D01*
X658361Y-209831D01*
X658797Y-207497D01*
X659671Y-205456D01*
X660981Y-204289D01*
X662291Y-203998D01*
X663601Y-204289D01*
X664911Y-205456D01*
X665784Y-207497D01*
X666003Y-209831D01*
X665784Y-212164D01*
X664911Y-214206D01*
X663601Y-215372D01*
X662291Y-215664D01*
G01X676079D02*
Y-203998D01*
G01Y-206914D02*
X676953Y-205456D01*
X678263Y-204289D01*
X680009Y-203998D01*
X681537Y-204289D01*
X682848Y-205456D01*
X683503Y-207497D01*
Y-215664D01*
G01X710424D02*
Y-198164D01*
X715883D01*
X717629Y-199039D01*
X718721Y-200206D01*
X719158Y-202539D01*
X718721Y-204873D01*
X717411Y-206331D01*
X715883Y-207206D01*
X710424D01*
G01X715883D02*
X719158Y-215664D01*
G01X732291Y-216247D02*
X731854Y-215956D01*
Y-215372D01*
X732291Y-215081D01*
X732728Y-215372D01*
Y-215956D01*
X732291Y-216247D01*
G01X744988Y-215664D02*
Y-198164D01*
X749354D01*
X751101Y-199039D01*
X752411Y-200206D01*
X753503Y-201955D01*
X754376Y-203998D01*
X754594Y-206914D01*
X754376Y-209831D01*
X753503Y-211873D01*
X752411Y-213623D01*
X751101Y-214789D01*
X749354Y-215664D01*
X744988D01*
G01X762924D02*
Y-198164D01*
X768164D01*
X769911Y-199039D01*
X771221Y-201081D01*
X771658Y-203414D01*
X771221Y-205747D01*
X770129Y-207497D01*
X768164Y-208373D01*
X762924D01*
G01X786537Y-206331D02*
X787411Y-205456D01*
X788066Y-203998D01*
X788503Y-201955D01*
X788066Y-200206D01*
X787193Y-199039D01*
X785664Y-198164D01*
X779769D01*
Y-215664D01*
X786974D01*
X788503Y-214498D01*
X789376Y-212747D01*
X789813Y-210706D01*
X789376Y-208664D01*
X788066Y-206914D01*
X786537Y-206331D01*
X779769D01*
G01X595364Y-170664D02*
Y-153164D01*
X601041Y-167747D01*
X606718Y-153164D01*
Y-170664D01*
G01X618541D02*
X617231Y-170372D01*
X615921Y-169206D01*
X615047Y-167164D01*
X614611Y-164831D01*
X615047Y-162497D01*
X615921Y-160456D01*
X617231Y-159289D01*
X618541Y-158998D01*
X619851Y-159289D01*
X621161Y-160456D01*
X622034Y-162497D01*
X622253Y-164831D01*
X622034Y-167164D01*
X621161Y-169206D01*
X619851Y-170372D01*
X618541Y-170664D01*
G01X639971Y-153164D02*
Y-170664D01*
G01Y-168040D02*
X639098Y-169498D01*
X637787Y-170372D01*
X636259Y-170664D01*
X634513Y-170081D01*
X633203Y-168623D01*
X632329Y-166873D01*
X632111Y-164831D01*
X632329Y-162789D01*
X633203Y-161039D01*
X634513Y-159581D01*
X636259Y-158998D01*
X637787Y-159289D01*
X638879Y-159873D01*
X639971Y-161039D01*
G01X650266Y-162789D02*
X657253D01*
X656598Y-160747D01*
X655506Y-159581D01*
X653978Y-158998D01*
X652449Y-159289D01*
X651139Y-160164D01*
X650266Y-162206D01*
X649829Y-163956D01*
Y-165706D01*
X650266Y-167456D01*
X651358Y-169206D01*
X652668Y-170372D01*
X654196Y-170664D01*
X655724Y-170081D01*
X657253Y-168331D01*
G01X671041Y-170664D02*
Y-153164D01*
G01X839441Y-215664D02*
Y-198164D01*
X836821Y-201664D01*
G01Y-215664D02*
X842061D01*
G01X852793Y-208373D02*
X854321Y-206331D01*
X855631Y-205164D01*
X857378Y-204581D01*
X858906Y-205164D01*
X859998Y-206331D01*
X860871Y-208081D01*
X861089Y-210122D01*
X860871Y-211873D01*
X859998Y-213623D01*
X858687Y-215081D01*
X857159Y-215664D01*
X855413Y-215081D01*
X853884Y-213331D01*
X853011Y-210706D01*
X852793Y-207789D01*
X853229Y-203998D01*
X853884Y-201955D01*
X854976Y-199914D01*
X856504Y-198456D01*
X858033Y-198164D01*
X859561Y-198747D01*
X860653Y-200206D01*
G01X869638Y-212164D02*
X870947Y-214206D01*
X872694Y-215372D01*
X874659Y-215664D01*
X876406Y-215372D01*
X878153Y-213914D01*
X879244Y-212164D01*
X879463Y-210414D01*
X879026Y-208373D01*
X877498Y-206914D01*
X875969Y-206331D01*
X874004D01*
G01X875969D02*
X877279Y-205456D01*
X878371Y-203998D01*
X878808Y-202248D01*
X878371Y-200497D01*
X877279Y-199039D01*
X875314Y-198164D01*
X873349Y-198456D01*
X871384Y-199623D01*
G01X891941Y-215664D02*
Y-198164D01*
X889321Y-201664D01*
G01Y-215664D02*
X894561D01*
G01X909004D02*
X909441Y-211873D01*
X910096Y-208664D01*
X910969Y-205747D01*
X912061Y-202539D01*
X913808Y-198164D01*
X905074D01*
G01X826324Y-170664D02*
Y-153164D01*
X831564D01*
X833311Y-154039D01*
X834621Y-156081D01*
X835058Y-158414D01*
X834621Y-160747D01*
X833529Y-162497D01*
X831564Y-163373D01*
X826324D01*
G01X852994Y-154623D02*
X851684Y-153747D01*
X850156Y-153164D01*
X848409D01*
X846444Y-154039D01*
X844916Y-155497D01*
X843824Y-157248D01*
X842951Y-160164D01*
X842732Y-162789D01*
X843169Y-165414D01*
X843824Y-167164D01*
X845134Y-168914D01*
X846663Y-170081D01*
X848191Y-170664D01*
X849719D01*
X851248Y-170081D01*
X852558Y-169206D01*
X853650Y-168040D01*
G01X867437Y-161331D02*
X868311Y-160456D01*
X868966Y-158998D01*
X869403Y-156955D01*
X868966Y-155206D01*
X868093Y-154039D01*
X866564Y-153164D01*
X860669D01*
Y-170664D01*
X867874D01*
X869403Y-169498D01*
X870276Y-167747D01*
X870713Y-165706D01*
X870276Y-163664D01*
X868966Y-161914D01*
X867437Y-161331D01*
X860669D01*
G01X876641Y-176497D02*
X889741D01*
G01X895669Y-170664D02*
Y-153164D01*
X905713Y-170664D01*
Y-153164D01*
G01X918191Y-170664D02*
X916444Y-170372D01*
X914916Y-169206D01*
X913606Y-167456D01*
X912732Y-165414D01*
X912296Y-163081D01*
Y-160747D01*
X912732Y-158414D01*
X913606Y-156372D01*
X914916Y-154623D01*
X916444Y-153456D01*
X918191Y-153164D01*
X919937Y-153456D01*
X921466Y-154623D01*
X922776Y-156372D01*
X923650Y-158414D01*
X924086Y-160747D01*
Y-163081D01*
X923650Y-165414D01*
X922776Y-167456D01*
X921466Y-169206D01*
X919937Y-170372D01*
X918191Y-170664D01*
G01X1000741Y-215664D02*
Y-198164D01*
X998121Y-201664D01*
G01Y-215664D02*
X1003361D01*
G01X969032Y-153164D02*
X974491Y-170664D01*
X979950Y-153164D01*
G01X996358Y-170664D02*
X987624D01*
Y-153164D01*
X996358D01*
G01X992864Y-161622D02*
X987624D01*
G01X1005124Y-170664D02*
Y-153164D01*
X1010583D01*
X1012329Y-154039D01*
X1013421Y-155206D01*
X1013858Y-157539D01*
X1013421Y-159873D01*
X1012111Y-161331D01*
X1010583Y-162206D01*
X1005124D01*
G01X1010583D02*
X1013858Y-170664D01*
G01X1026991Y-171247D02*
X1026554Y-170956D01*
Y-170372D01*
X1026991Y-170081D01*
X1027428Y-170372D01*
Y-170956D01*
X1026991Y-171247D01*
G01X1115691Y-198164D02*
Y-215664D01*
G01X1110669Y-198164D02*
X1120713D01*
G01X1128606Y-213331D02*
X1130353Y-214789D01*
X1132318Y-215664D01*
X1134064D01*
X1135811Y-214789D01*
X1137121Y-213331D01*
X1137776Y-211289D01*
X1137339Y-209248D01*
X1136248Y-207497D01*
X1134283Y-206331D01*
X1131663Y-205747D01*
X1130134Y-204581D01*
X1129479Y-202539D01*
X1129916Y-200497D01*
X1131008Y-199039D01*
X1132536Y-198164D01*
X1134064D01*
X1135593Y-198747D01*
X1136903Y-200206D01*
G01X1145014Y-215664D02*
Y-198164D01*
X1150691Y-212747D01*
X1156368Y-198164D01*
Y-215664D01*
G01X1163388D02*
Y-198164D01*
X1167754D01*
X1169501Y-199039D01*
X1170811Y-200206D01*
X1171903Y-201955D01*
X1172776Y-203998D01*
X1172994Y-206914D01*
X1172776Y-209831D01*
X1171903Y-211873D01*
X1170811Y-213623D01*
X1169501Y-214789D01*
X1167754Y-215664D01*
X1163388D01*
G01X1102574Y-153164D02*
Y-170664D01*
X1111308D01*
G01X1128371D02*
Y-158998D01*
G01Y-161039D02*
X1127498Y-159873D01*
X1126187Y-159289D01*
X1124659Y-158998D01*
X1123131Y-159581D01*
X1121821Y-160747D01*
X1120947Y-162497D01*
X1120511Y-164831D01*
X1120947Y-167164D01*
X1121821Y-168914D01*
X1123131Y-170081D01*
X1124659Y-170664D01*
X1126187Y-170372D01*
X1127498Y-169498D01*
X1128371Y-168331D01*
G01X1137356Y-175914D02*
X1138666Y-176497D01*
X1140413Y-175914D01*
X1141504Y-174748D01*
X1142378Y-173289D01*
X1143687Y-168623D01*
X1146526Y-158998D01*
G01X1139539D02*
X1143687Y-168623D01*
G01X1156166Y-162789D02*
X1163153D01*
X1162498Y-160747D01*
X1161406Y-159581D01*
X1159878Y-158998D01*
X1158349Y-159289D01*
X1157039Y-160164D01*
X1156166Y-162206D01*
X1155729Y-163956D01*
Y-165706D01*
X1156166Y-167456D01*
X1157258Y-169206D01*
X1158568Y-170372D01*
X1160096Y-170664D01*
X1161624Y-170081D01*
X1163153Y-168331D01*
G01X1173884Y-170664D02*
Y-158998D01*
G01Y-161331D02*
X1174976Y-160164D01*
X1176068Y-159289D01*
X1177596Y-158998D01*
X1178687Y-159289D01*
X1179998Y-160164D01*
G01X1244688Y-170664D02*
Y-153164D01*
X1249054D01*
X1250801Y-154039D01*
X1252111Y-155206D01*
X1253203Y-156955D01*
X1254076Y-158998D01*
X1254294Y-161914D01*
X1254076Y-164831D01*
X1253203Y-166873D01*
X1252111Y-168623D01*
X1250801Y-169789D01*
X1249054Y-170664D01*
X1244688D01*
G01X1263716Y-162789D02*
X1270703D01*
X1270048Y-160747D01*
X1268956Y-159581D01*
X1267428Y-158998D01*
X1265899Y-159289D01*
X1264589Y-160164D01*
X1263716Y-162206D01*
X1263279Y-163956D01*
Y-165706D01*
X1263716Y-167456D01*
X1264808Y-169206D01*
X1266118Y-170372D01*
X1267646Y-170664D01*
X1269174Y-170081D01*
X1270703Y-168331D01*
G01X1281216Y-168623D02*
X1282308Y-169789D01*
X1283836Y-170664D01*
X1285146D01*
X1286456Y-170081D01*
X1287329Y-169206D01*
X1287766Y-168040D01*
X1287548Y-166289D01*
X1286674Y-165414D01*
X1282744Y-163664D01*
X1281871Y-161622D01*
X1282308Y-160164D01*
X1283181Y-159289D01*
X1284491Y-158998D01*
X1285801Y-159289D01*
X1287111Y-160164D01*
G01X1301991Y-158998D02*
Y-170664D01*
G01Y-154331D02*
X1301554Y-154039D01*
Y-153456D01*
X1301991Y-153164D01*
X1302428Y-153456D01*
Y-154039D01*
X1301991Y-154331D01*
G01X1316434Y-175039D02*
X1317963Y-176206D01*
X1319709Y-176497D01*
X1321237Y-176206D01*
X1322548Y-174748D01*
X1323421Y-172706D01*
Y-158998D01*
G01Y-161331D02*
X1322548Y-160164D01*
X1321237Y-159289D01*
X1319709Y-158998D01*
X1317963Y-159581D01*
X1316871Y-160747D01*
X1315997Y-162789D01*
X1315561Y-164831D01*
X1315779Y-166581D01*
X1316653Y-168623D01*
X1317963Y-170081D01*
X1319709Y-170664D01*
X1321019Y-170372D01*
X1322548Y-169206D01*
X1323421Y-168040D01*
G01X1333279Y-170664D02*
Y-158998D01*
G01Y-161914D02*
X1334153Y-160456D01*
X1335463Y-159289D01*
X1337209Y-158998D01*
X1338737Y-159289D01*
X1340048Y-160456D01*
X1340703Y-162497D01*
Y-170664D01*
G01X1351216Y-162789D02*
X1358203D01*
X1357548Y-160747D01*
X1356456Y-159581D01*
X1354928Y-158998D01*
X1353399Y-159289D01*
X1352089Y-160164D01*
X1351216Y-162206D01*
X1350779Y-163956D01*
Y-165706D01*
X1351216Y-167456D01*
X1352308Y-169206D01*
X1353618Y-170372D01*
X1355146Y-170664D01*
X1356674Y-170081D01*
X1358203Y-168331D01*
G01X1368934Y-170664D02*
Y-158998D01*
G01Y-161331D02*
X1370026Y-160164D01*
X1371118Y-159289D01*
X1372646Y-158998D01*
X1373737Y-159289D01*
X1375048Y-160164D01*
G01X1266991Y-215664D02*
X1265244Y-215372D01*
X1263716Y-214206D01*
X1262406Y-212456D01*
X1261532Y-210414D01*
X1261096Y-208081D01*
Y-205747D01*
X1261532Y-203414D01*
X1262406Y-201372D01*
X1263716Y-199623D01*
X1265244Y-198456D01*
X1266991Y-198164D01*
X1268737Y-198456D01*
X1270266Y-199623D01*
X1271576Y-201372D01*
X1272450Y-203414D01*
X1272886Y-205747D01*
Y-208081D01*
X1272450Y-210414D01*
X1271576Y-212456D01*
X1270266Y-214206D01*
X1268737Y-215372D01*
X1266991Y-215664D01*
G01X1268737Y-210997D02*
X1271358Y-215664D01*
G01X1279688Y-198164D02*
Y-210706D01*
X1280561Y-213331D01*
X1282308Y-215081D01*
X1284491Y-215664D01*
X1286674Y-215081D01*
X1288421Y-213331D01*
X1289294Y-210706D01*
Y-198164D01*
G01X1299371D02*
X1304611D01*
G01X1301991D02*
Y-215664D01*
G01X1299371D02*
X1304611D01*
G01X1314469D02*
Y-198164D01*
X1324513Y-215664D01*
Y-198164D01*
G01X1341794Y-199623D02*
X1340484Y-198747D01*
X1338956Y-198164D01*
X1337209D01*
X1335244Y-199039D01*
X1333716Y-200497D01*
X1332624Y-202248D01*
X1331751Y-205164D01*
X1331532Y-207789D01*
X1331969Y-210414D01*
X1332624Y-212164D01*
X1333934Y-213914D01*
X1335463Y-215081D01*
X1336991Y-215664D01*
X1338519D01*
X1340048Y-215081D01*
X1341358Y-214206D01*
X1342450Y-213040D01*
G01X1354491Y-215664D02*
Y-207789D01*
X1350124Y-198164D01*
G01X1358858D02*
X1354491Y-207789D01*
G01X1415691Y-198164D02*
X1413944Y-198747D01*
X1412634Y-200206D01*
X1411761Y-201955D01*
X1411106Y-204289D01*
X1410888Y-206914D01*
X1411106Y-209539D01*
X1411761Y-211873D01*
X1412634Y-213623D01*
X1413944Y-215081D01*
X1415691Y-215664D01*
X1417437Y-215081D01*
X1418748Y-213623D01*
X1419621Y-211873D01*
X1420276Y-209539D01*
X1420494Y-206914D01*
X1420276Y-204289D01*
X1419621Y-201955D01*
X1418748Y-200206D01*
X1417437Y-198747D01*
X1415691Y-198164D01*
G01X1429043Y-208373D02*
X1430571Y-206331D01*
X1431881Y-205164D01*
X1433628Y-204581D01*
X1435156Y-205164D01*
X1436248Y-206331D01*
X1437121Y-208081D01*
X1437339Y-210122D01*
X1437121Y-211873D01*
X1436248Y-213623D01*
X1434937Y-215081D01*
X1433409Y-215664D01*
X1431663Y-215081D01*
X1430134Y-213331D01*
X1429261Y-210706D01*
X1429043Y-207789D01*
X1429479Y-203998D01*
X1430134Y-201955D01*
X1431226Y-199914D01*
X1432754Y-198456D01*
X1434283Y-198164D01*
X1435811Y-198747D01*
X1436903Y-200206D01*
G01X1446761Y-216247D02*
X1454621Y-198164D01*
G01X1468191D02*
X1466444Y-198747D01*
X1465134Y-200206D01*
X1464261Y-201955D01*
X1463606Y-204289D01*
X1463388Y-206914D01*
X1463606Y-209539D01*
X1464261Y-211873D01*
X1465134Y-213623D01*
X1466444Y-215081D01*
X1468191Y-215664D01*
X1469937Y-215081D01*
X1471248Y-213623D01*
X1472121Y-211873D01*
X1472776Y-209539D01*
X1472994Y-206914D01*
X1472776Y-204289D01*
X1472121Y-201955D01*
X1471248Y-200206D01*
X1469937Y-198747D01*
X1468191Y-198164D01*
G01X1481979Y-213623D02*
X1483508Y-215081D01*
X1485254Y-215664D01*
X1487001Y-215081D01*
X1488529Y-213331D01*
X1489621Y-210706D01*
X1490058Y-208081D01*
Y-204873D01*
X1489621Y-202248D01*
X1488529Y-199914D01*
X1487219Y-198747D01*
X1485691Y-198164D01*
X1483944Y-198747D01*
X1482634Y-199914D01*
X1481761Y-201664D01*
X1481324Y-203998D01*
X1481761Y-206039D01*
X1482853Y-208081D01*
X1484163Y-209248D01*
X1485691Y-209539D01*
X1487437Y-208956D01*
X1488748Y-207497D01*
X1490058Y-204873D01*
G01X1499261Y-216247D02*
X1507121Y-198164D01*
G01X1516543Y-201081D02*
X1517853Y-199331D01*
X1519381Y-198456D01*
X1521128Y-198164D01*
X1523311Y-198747D01*
X1524839Y-200206D01*
X1525276Y-201955D01*
X1525058Y-203706D01*
X1524184Y-205164D01*
X1519818Y-208081D01*
X1517853Y-210122D01*
X1516543Y-213040D01*
X1516106Y-215664D01*
X1525276D01*
G01X1538191Y-198164D02*
X1536444Y-198747D01*
X1535134Y-200206D01*
X1534261Y-201955D01*
X1533606Y-204289D01*
X1533388Y-206914D01*
X1533606Y-209539D01*
X1534261Y-211873D01*
X1535134Y-213623D01*
X1536444Y-215081D01*
X1538191Y-215664D01*
X1539937Y-215081D01*
X1541248Y-213623D01*
X1542121Y-211873D01*
X1542776Y-209539D01*
X1542994Y-206914D01*
X1542776Y-204289D01*
X1542121Y-201955D01*
X1541248Y-200206D01*
X1539937Y-198747D01*
X1538191Y-198164D01*
G01X1555691Y-215664D02*
Y-198164D01*
X1553071Y-201664D01*
G01Y-215664D02*
X1558311D01*
G01X1572754D02*
X1573191Y-211873D01*
X1573846Y-208664D01*
X1574719Y-205747D01*
X1575811Y-202539D01*
X1577558Y-198164D01*
X1568824D01*
G01X1463388Y-170664D02*
Y-153164D01*
X1467754D01*
X1469501Y-154039D01*
X1470811Y-155206D01*
X1471903Y-156955D01*
X1472776Y-158998D01*
X1472994Y-161914D01*
X1472776Y-164831D01*
X1471903Y-166873D01*
X1470811Y-168623D01*
X1469501Y-169789D01*
X1467754Y-170664D01*
X1463388D01*
G01X1489621D02*
Y-158998D01*
G01Y-161039D02*
X1488748Y-159873D01*
X1487437Y-159289D01*
X1485909Y-158998D01*
X1484381Y-159581D01*
X1483071Y-160747D01*
X1482197Y-162497D01*
X1481761Y-164831D01*
X1482197Y-167164D01*
X1483071Y-168914D01*
X1484381Y-170081D01*
X1485909Y-170664D01*
X1487437Y-170372D01*
X1488748Y-169498D01*
X1489621Y-168331D01*
G01X1503191Y-153164D02*
Y-170664D01*
G01X1500134Y-158998D02*
X1506248D01*
G01X1517416Y-162789D02*
X1524403D01*
X1523748Y-160747D01*
X1522656Y-159581D01*
X1521128Y-158998D01*
X1519599Y-159289D01*
X1518289Y-160164D01*
X1517416Y-162206D01*
X1516979Y-163956D01*
Y-165706D01*
X1517416Y-167456D01*
X1518508Y-169206D01*
X1519818Y-170372D01*
X1521346Y-170664D01*
X1522874Y-170081D01*
X1524403Y-168331D01*
G01X0Y3937D02*
G03X3937Y0I3937J0D01*
G01X0Y3937D02*
G03X3937Y0I3937J0D01*
G01D02*
X779528D01*
G01X3937D02*
X779528D01*
G01X0Y1456693D02*
Y3937D01*
G01Y1456693D02*
Y3937D01*
G01X7874Y1460630D02*
X3937D01*
G01D02*
X7874D01*
G01X3937D02*
G03X0Y1456693I0J-3937D01*
G01X3937Y1460630D02*
G03X0Y1456693I0J-3937D01*
G01X101378Y1519685D02*
G03X97441Y1515748I0J-3937D01*
G01X101378Y1519685D02*
G03X97441Y1515748I0J-3937D01*
G01D02*
Y1509055D01*
G01Y1515748D02*
Y1509055D01*
G01X93504Y1505118D02*
X67913D01*
G01X93504D02*
G03X97441Y1509055I0J3937D01*
G01X93504Y1505118D02*
G03X97441Y1509055I0J3937D01*
G01X67913Y1505118D02*
X93504D01*
G01X63976Y1515748D02*
G03X60039Y1519685I-3937J0D01*
G01X63976Y1515748D02*
G03X60039Y1519685I-3937J0D01*
G01X63976Y1509055D02*
Y1515748D01*
G01Y1509055D02*
G03X67913Y1505118I3937J0D01*
G01X63976Y1509055D02*
G03X67913Y1505118I3937J0D01*
G01X63976Y1515748D02*
Y1509055D01*
G01X7874Y1460630D02*
G03X11811Y1464567I0J3937D01*
G01X7874Y1460630D02*
G03X11811Y1464567I0J3937D01*
G01X15748Y1519685D02*
G03X11811Y1515748I0J-3937D01*
G01X15748Y1519685D02*
G03X11811Y1515748I0J-3937D01*
G01D02*
Y1464567D01*
G01Y1515748D02*
Y1464567D01*
G01X60039Y1519685D02*
X15748D01*
G01X60039D02*
X15748D01*
G01X141181Y277843D02*
G03X148106Y264712I37662J11471D01*
G01X141181Y277843D02*
G03X148106Y264712I37662J11471D01*
G01X141181Y277843D02*
G03X121220I-9980J-3040D01*
G01X114295Y264712D02*
G03X121220Y277843I-30737J24602D01*
G01X141181D02*
G03X121220I-9980J-3040D01*
G01X114295Y264712D02*
G03X121220Y277843I-30737J24601D01*
G01X114295Y264712D02*
G03X148106I16905J-13531D01*
G01X114295D02*
G03X148106I16905J-13531D01*
G01X141181Y730599D02*
G03X148106Y717468I37662J11471D01*
G01X141181Y730599D02*
G03X148106Y717468I37662J11471D01*
G01X141181Y730599D02*
G03X121220I-9980J-3040D01*
G01X114295Y717468D02*
G03X121220Y730599I-30737J24601D01*
G01X141181D02*
G03X121220I-9980J-3040D01*
G01X114295Y717468D02*
G03X121220Y730599I-30737J24601D01*
G01X114295Y717468D02*
G03X148106I16905J-13531D01*
G01X114295D02*
G03X148106I16905J-13531D01*
G01X114295Y1170224D02*
G03X148106I16905J-13531D01*
G01X114295D02*
G03X148106I16905J-13531D01*
G01X141181Y1183355D02*
G03X148106Y1170224I37662J11471D01*
G01X141181Y1183355D02*
G03X148106Y1170224I37662J11471D01*
G01X141181Y1183355D02*
G03X121220I-9980J-3040D01*
G01X141181D02*
G03X121220I-9980J-3040D01*
G01X114295Y1170224D02*
G03X121220Y1183355I-30737J24602D01*
G01X114295Y1170224D02*
G03X121220Y1183355I-30737J24601D01*
G01X280709Y1519685D02*
X101378D01*
G01X280709D02*
X101378D01*
G01X284646Y1515748D02*
G03X280709Y1519685I-3937J0D01*
G01X284646Y1515748D02*
G03X280709Y1519685I-3937J0D01*
G01X284646Y1500000D02*
Y1515748D01*
G01Y1500000D02*
G03X288583Y1496063I3937J0D01*
G01X493307D02*
X288583D01*
G01X284646Y1500000D02*
G03X288583Y1496063I3937J0D01*
G01X493307D02*
X288583D01*
G01X284646Y1515748D02*
Y1500000D01*
G01X389213Y277843D02*
G03X369252I-9981J-3040D01*
G01X389213D02*
G03X369252I-9981J-3040D01*
G01X362327Y264712D02*
G03X369252Y277843I-30737J24602D01*
G01X362327Y264712D02*
G03X369252Y277843I-30737J24602D01*
G01X362327Y264712D02*
G03X396138I16905J-13531D01*
G01X362327D02*
G03X396138I16905J-13531D01*
G01X389213Y730599D02*
G03X369252I-9981J-3040D01*
G01X389213D02*
G03X369252I-9981J-3040D01*
G01X362327Y717468D02*
G03X369252Y730599I-30737J24602D01*
G01X362327Y717468D02*
G03X369252Y730599I-30737J24602D01*
G01X362327Y717468D02*
G03X396138I16905J-13531D01*
G01X362327D02*
G03X396138I16905J-13531D01*
G01X362327Y1170224D02*
G03X396138I16905J-13531D01*
G01X362327D02*
G03X396138I16905J-13531D01*
G01X389213Y1183355D02*
G03X369252I-9981J-3040D01*
G01X389213D02*
G03X369252I-9981J-3040D01*
G01X362327Y1170224D02*
G03X369252Y1183355I-30737J24602D01*
G01X362327Y1170224D02*
G03X369252Y1183355I-30737J24602D01*
G01X322441Y1503937D02*
G03Y1496063I0J-3937D01*
G01X459449Y1503937D02*
X322441D01*
G01X459449D02*
X322441D01*
G01D02*
G03Y1496063I0J-3937D01*
G01X296457Y1519685D02*
G03X292520Y1515748I0J-3937D01*
G01X296457Y1519685D02*
X485433D01*
G01X296457D02*
G03X292520Y1515748I0J-3937D01*
G01X296457Y1519685D02*
X485433D01*
G01X304331Y1503937D02*
X292520D01*
G01Y1515748D02*
Y1503937D01*
G01X304331D02*
X292520D01*
G01Y1515748D02*
Y1503937D01*
G01X304331Y1496063D02*
G03Y1503937I0J3937D01*
G01Y1496063D02*
G03Y1503937I0J3937D01*
G01X389213Y277843D02*
G03X396138Y264712I37662J11471D01*
G01X389213Y277843D02*
G03X396138Y264712I37662J11470D01*
G01X389213Y730599D02*
G03X396138Y717468I37662J11471D01*
G01X389213Y730599D02*
G03X396138Y717468I37662J11470D01*
G01X389213Y1183355D02*
G03X396138Y1170224I37662J11471D01*
G01X389213Y1183355D02*
G03X396138Y1170224I37662J11470D01*
G01X477559Y1503937D02*
G03Y1496063I0J-3937D01*
G01X459449D02*
G03Y1503937I0J3937D01*
G01X489370D02*
X477559D01*
G01D02*
G03Y1496063I0J-3937D01*
G01X459449D02*
G03Y1503937I0J3937D01*
G01X489370D02*
X477559D01*
G01X489370Y1515748D02*
G03X485433Y1519685I-3937J0D01*
G01X489370Y1515748D02*
G03X485433Y1519685I-3937J0D01*
G01X501181D02*
G03X497244Y1515748I0J-3937D01*
G01X680512Y1519685D02*
X501181D01*
G01D02*
G03X497244Y1515748I0J-3937D01*
G01X680512Y1519685D02*
X501181D01*
G01X489370Y1515748D02*
Y1503937D01*
G01X493307Y1496063D02*
G03X497244Y1500000I0J3937D01*
G01Y1515748D02*
Y1500000D01*
G01X489370Y1515748D02*
Y1503937D01*
G01X493307Y1496063D02*
G03X497244Y1500000I0J3937D01*
G01Y1515748D02*
Y1500000D01*
G01X637244Y277843D02*
G03X644169Y264712I37662J11471D01*
G01X637244Y277843D02*
G03X644169Y264712I37662J11471D01*
G01X637244Y277843D02*
G03X617283I-9980J-3040D01*
G01X610358Y264712D02*
G03X617283Y277843I-30737J24602D01*
G01X637244D02*
G03X617283I-9980J-3040D01*
G01X610358Y264712D02*
G03X617283Y277843I-30737J24601D01*
G01X610358Y264712D02*
G03X644169I16906J-13531D01*
G01X610358D02*
G03X644169I16906J-13531D01*
G01X637244Y730599D02*
G03X644169Y717468I37662J11471D01*
G01X637244Y730599D02*
G03X644169Y717468I37662J11471D01*
G01X637244Y730599D02*
G03X617283I-9980J-3040D01*
G01X610358Y717468D02*
G03X617283Y730599I-30737J24601D01*
G01X637244D02*
G03X617283I-9980J-3040D01*
G01X610358Y717468D02*
G03X617283Y730599I-30737J24601D01*
G01X610358Y717468D02*
G03X644169I16906J-13531D01*
G01X610358D02*
G03X644169I16906J-13531D01*
G01X610358Y1170224D02*
G03X644169I16906J-13531D01*
G01X610358D02*
G03X644169I16906J-13531D01*
G01X637244Y1183355D02*
G03X644169Y1170224I37662J11471D01*
G01X637244Y1183355D02*
G03X644169Y1170224I37662J11471D01*
G01X637244Y1183355D02*
G03X617283I-9980J-3040D01*
G01X637244D02*
G03X617283I-9980J-3040D01*
G01X610358Y1170224D02*
G03X617283Y1183355I-30737J24602D01*
G01X610358Y1170224D02*
G03X617283Y1183355I-30737J24601D01*
G01X730339Y383610D02*
G03X764149I16905J-13531D01*
G01X730339Y383609D02*
G03X764150I16905J-13530D01*
G01X757225Y396741D02*
G03X764149Y383610I37663J11469D01*
G01X757224Y396741D02*
G03X764150Y383609I37662J11471D01*
G01X757225Y396741D02*
G03X737264I-9981J-3040D01*
G01X730339Y383610D02*
G03X737264Y396741I-30737J24602D01*
G01X757224D02*
G03X737264I-9980J-3041D01*
G01X730339Y383609D02*
G03X737264Y396741I-30738J24601D01*
G01X757225Y829811D02*
G03X764149Y816680I37663J11469D01*
G01X757224Y829811D02*
G03X764150Y816680I37662J11473D01*
G01X757225Y829811D02*
G03X737264I-9981J-3039D01*
G01X757224D02*
G03X737264I-9980J-3040D01*
G01X730339Y816680D02*
G03X737264Y829811I-30737J24602D01*
G01X730339Y816680D02*
G03X737264Y829811I-30737J24602D01*
G01X730339Y816680D02*
G03X764149I16905J-13531D01*
G01X730339D02*
G03X764150I16905J-13531D01*
G01X721850Y1519685D02*
G03X717913Y1515748I0J-3937D01*
G01X775591Y1519685D02*
X721850D01*
G01D02*
G03X717913Y1515748I0J-3937D01*
G01X775591Y1519685D02*
X721850D01*
G01X713976Y1505118D02*
G03X717913Y1509055I0J3937D01*
G01Y1515748D02*
Y1509055D01*
G01X713976Y1505118D02*
G03X717913Y1509055I0J3937D01*
G01Y1515748D02*
Y1509055D01*
G01X684449Y1515748D02*
G03X680512Y1519685I-3937J0D01*
G01X684449Y1515748D02*
G03X680512Y1519685I-3937J0D01*
G01X684449Y1509055D02*
Y1515748D01*
G01Y1509055D02*
G03X688386Y1505118I3937J0D01*
G01X713976D02*
X688386D01*
G01X684449Y1509055D02*
G03X688386Y1505118I3937J0D01*
G01D02*
X713976D01*
G01X684449Y1515748D02*
Y1509055D01*
G01X791339Y3937D02*
G03X795276Y0I3937J0D01*
G01D02*
X892317D01*
G01X791339Y3937D02*
Y23622D01*
G01Y3937D02*
G03X795276Y0I3937J0D01*
G01X791339Y3937D02*
Y23622D01*
G01X795276Y0D02*
X892317D01*
G01X783465Y54331D02*
G03X791339I3937J0D01*
G01X783465D02*
G03X791339I3937J0D01*
G01Y23622D02*
G03X783465I-3937J0D01*
G01X791339D02*
G03X783465I-3937J0D01*
G01X779528Y0D02*
G03X783465Y3937I0J3937D01*
G01X779528Y0D02*
G03X783465Y3937I0J3937D01*
G01X791339Y54331D02*
Y181890D01*
G01Y54331D02*
Y181890D01*
G01X783465Y3937D02*
Y185827D01*
G01Y3937D02*
Y185827D01*
G01X811024Y181890D02*
G03X822835Y193701I0J11811D01*
G01X791339Y181890D02*
X811024D01*
G01D02*
G03X822835Y193701I0J11811D01*
G01X791339Y181890D02*
X811024D01*
G01X787402Y189764D02*
G03X783465Y185827I0J-3937D01*
G01X787402Y189764D02*
G03X783465Y185827I0J-3937D01*
G01X811024Y189764D02*
G03X814961Y193701I0J3937D01*
G01X787402Y189764D02*
X811024D01*
G01D02*
G03X814961Y193701I0J3937D01*
G01X787402Y189764D02*
X811024D01*
G01X822835Y193701D02*
Y240157D01*
G01Y193701D02*
Y240157D01*
G01X814961Y193701D02*
Y244094D01*
G01Y193701D02*
Y244094D01*
G01X818898Y248031D02*
G03X814961Y244094I0J-3937D01*
G01X818898Y248031D02*
G03X814961Y244094I0J-3937D01*
G01X928098Y240157D02*
X822835D01*
G01X928098D02*
X822835D01*
G01X818898Y248031D02*
X1055118D01*
G01D02*
X818898D01*
G01X954331Y1503937D02*
X817323D01*
G01X954331D02*
X817323D01*
G01X791339Y1519685D02*
G03X787402Y1515748I0J-3937D01*
G01X791339Y1519685D02*
X980315D01*
G01X791339D02*
G03X787402Y1515748I0J-3937D01*
G01X791339Y1519685D02*
X980315D01*
G01X817323Y1503937D02*
G03Y1496063I0J-3937D01*
G01X799213D02*
G03Y1503937I0J3937D01*
G01D02*
X787402D01*
G01Y1515748D02*
Y1503937D01*
G01X799213D02*
X787402D01*
G01X817323D02*
G03Y1496063I0J-3937D01*
G01X799213D02*
G03Y1503937I0J3937D01*
G01X787402Y1515748D02*
Y1503937D01*
G01X779528Y1515748D02*
G03X775591Y1519685I-3937J0D01*
G01X779528Y1515748D02*
G03X775591Y1519685I-3937J0D01*
G01X779528Y1500000D02*
Y1515748D01*
G01Y1500000D02*
G03X783465Y1496063I3937J0D01*
G01X988189D02*
X783465D01*
G01X779528Y1500000D02*
G03X783465Y1496063I3937J0D01*
G01X988189D02*
X783465D01*
G01X779528Y1515748D02*
Y1500000D01*
G01X900191Y0D02*
G03X892317I-3937J0D01*
G01X896254D02*
Y-394D01*
G01Y0D02*
Y394D01*
G01X895762Y0D02*
X896746D01*
G01X900191D02*
G03X892317I-3937J0D01*
G01X900191D02*
X1212598D01*
G01X900191D02*
X1212598D01*
G01X953294Y248031D02*
G03Y240157I1J-3937D01*
G01X1051181D02*
X953294D01*
G01Y248031D02*
G03Y240157I1J-3937D01*
G01X928098D02*
G03Y248031I0J3937D01*
G01Y240157D02*
G03Y248031I0J3937D01*
G01X1051181Y240157D02*
X953294D01*
G01X971398Y718788D02*
G03X951437I-9980J-3040D01*
G01X944512Y705657D02*
G03X951437Y718788I-30737J24602D01*
G01X971398D02*
G03X951437I-9980J-3040D01*
G01X944512Y705657D02*
G03X951437Y718788I-30737J24602D01*
G01X944512Y705657D02*
G03X978323I16905J-13531D01*
G01X944512D02*
G03X978323I16905J-13531D01*
G01X944512Y974161D02*
G03X978323I16905J-13531D01*
G01X944512D02*
G03X978323I16905J-13531D01*
G01X971398Y987292D02*
G03X951437I-9980J-3040D01*
G01X944512Y974161D02*
G03X951437Y987292I-30737J24602D01*
G01X971398D02*
G03X951437I-9980J-3040D01*
G01X944512Y974161D02*
G03X951437Y987292I-30737J24602D01*
G01X954331Y1496063D02*
G03Y1503937I0J3937D01*
G01Y1496063D02*
G03Y1503937I0J3937D01*
G01X1051181Y193701D02*
G03X1062992Y181890I11811J0D01*
G01X1051181Y193701D02*
G03X1062992Y181890I11811J0D01*
G01X1051181Y240157D02*
Y193701D01*
G01Y240157D02*
Y193701D01*
G01X971398Y718788D02*
G03X978323Y705657I37662J11471D01*
G01X971398Y718788D02*
G03X978323Y705657I37662J11470D01*
G01X971398Y987292D02*
G03X978323Y974161I37662J11471D01*
G01X971398Y987292D02*
G03X978323Y974161I37662J11470D01*
G01X1059196Y1519685D02*
X996063D01*
G01X1059196D02*
X996063D01*
G01X984252Y1515748D02*
G03X980315Y1519685I-3937J0D01*
G01X984252Y1515748D02*
G03X980315Y1519685I-3937J0D01*
G01X996063D02*
G03X992126Y1515748I0J-3937D01*
G01X996063Y1519685D02*
G03X992126Y1515748I0J-3937D01*
G01X972441Y1503937D02*
G03Y1496063I0J-3937D01*
G01X984252Y1503937D02*
X972441D01*
G01X984252Y1515748D02*
Y1503937D01*
G01X972441D02*
G03Y1496063I0J-3937D01*
G01X988189D02*
G03X992126Y1500000I0J3937D01*
G01Y1515748D02*
Y1500000D01*
G01X984252Y1515748D02*
Y1503937D01*
G01D02*
X972441D01*
G01X988189Y1496063D02*
G03X992126Y1500000I0J3937D01*
G01Y1515748D02*
Y1500000D01*
G01X1133071Y189764D02*
G03Y181890I0J-3937D01*
G01D02*
X1216535D01*
G01X1133071D02*
X1216535D01*
G01X1133071Y189764D02*
G03Y181890I0J-3937D01*
G01X1102362D02*
G03Y189764I0J3937D01*
G01Y181890D02*
G03Y189764I0J3937D01*
G01X1062992Y181890D02*
X1102362D01*
G01X1062992D02*
X1102362D01*
G01X1059055Y244094D02*
G03X1055118Y248031I-3937J0D01*
G01X1059055Y244094D02*
G03X1055118Y248031I-3937J0D01*
G01X1059055Y244094D02*
Y193701D01*
G01Y244094D02*
Y193701D01*
G01X1062992Y189764D02*
X1220472D01*
G01X1059055Y193701D02*
G03X1062992Y189764I3937J0D01*
G01X1059055Y193701D02*
G03X1062992Y189764I3937J0D01*
G01D02*
X1220472D01*
G01X1085630Y1417323D02*
G03X1089567Y1421260I0J3937D01*
G01X1085630Y1417323D02*
G03X1089567Y1421260I0J3937D01*
G01X1072638D02*
G03X1076575Y1417322I3937J-1D01*
G01X1085630Y1417323D02*
X1076575D01*
G01X1072638Y1421260D02*
G03X1076575Y1417323I3937J0D01*
G01D02*
X1085630D01*
G01X1089567Y1506243D02*
Y1421260D01*
G01Y1506243D02*
Y1421260D01*
G01X1072638D02*
Y1506243D01*
G01D02*
Y1421260D01*
G01X1103009Y1519685D02*
G03X1100225Y1518532I0J-3937D01*
G01X1207283Y1519685D02*
X1103009D01*
G01D02*
G03X1100225Y1518532I0J-3937D01*
G01X1207283Y1519685D02*
X1103009D01*
G01X1090720Y1509027D02*
G03X1089567Y1506243I2784J-2784D01*
G01X1100225Y1518532D02*
X1090720Y1509027D01*
G01D02*
G03X1089567Y1506243I2784J-2784D01*
G01X1100225Y1518532D02*
X1090720Y1509027D01*
G01X1061980Y1518532D02*
G03X1059196Y1519685I-2784J-2784D01*
G01X1061980Y1518532D02*
G03X1059196Y1519685I-2784J-2784D01*
G01X1071485Y1509027D02*
X1061980Y1518532D01*
G01X1072638Y1506243D02*
G03X1071485Y1509027I-3937J0D01*
G01X1072638Y1506243D02*
G03X1071485Y1509027I-3937J0D01*
G01X1061980Y1518532D02*
X1071485Y1509027D01*
G01X1216535Y54331D02*
G03X1224409I3937J0D01*
G01X1216535D02*
Y181890D01*
G01Y54331D02*
Y181890D01*
G01Y54331D02*
G03X1224409I3937J0D01*
G01Y23622D02*
G03X1216535I-3937J0D01*
G01X1224409D02*
G03X1216535I-3937J0D01*
G01X1212598Y0D02*
G03X1216535Y3937I0J3937D01*
G01D02*
Y23622D01*
G01X1212598Y0D02*
G03X1216535Y3937I0J3937D01*
G01X1224409D02*
G03X1228346Y0I3937J0D01*
G01X1224409Y185827D02*
Y3937D01*
G01X1216535D02*
Y23622D01*
G01X1224409Y3937D02*
G03X1228346Y0I3937J0D01*
G01X1224409Y3937D02*
Y185827D01*
G01X1228346Y0D02*
X1930906D01*
G01X1228346D02*
X1930906D01*
G01X1224409Y185827D02*
G03X1220472Y189764I-3937J0D01*
G01X1224409Y185827D02*
G03X1220472Y189764I-3937J0D01*
G01X1164984Y383609D02*
G03X1198795I16906J-13530D01*
G01X1164984D02*
G03X1198795I16906J-13530D01*
G01X1191870Y396741D02*
G03X1198795Y383610I37662J11471D01*
G01X1191870Y396741D02*
G03X1198795Y383609I37663J11469D01*
G01X1191870Y396741D02*
G03X1171909I-9980J-3040D01*
G01X1164984Y383610D02*
G03X1171909Y396741I-30737J24602D01*
G01X1191870D02*
G03X1171909I-9980J-3040D01*
G01X1164984Y383609D02*
G03X1171909Y396741I-30737J24601D01*
G01X1164984Y974161D02*
G03X1198795I16906J-13531D01*
G01X1164984D02*
G03X1198795I16906J-13531D01*
G01X1191870Y987292D02*
G03X1198795Y974161I37662J11471D01*
G01X1191870Y987292D02*
G03X1198795Y974161I37662J11471D01*
G01X1191870Y987292D02*
G03X1171909I-9980J-3040D01*
G01X1164984Y974161D02*
G03X1171909Y987292I-30737J24602D01*
G01X1191870D02*
G03X1171909I-9980J-3040D01*
G01X1164984Y974161D02*
G03X1171909Y987292I-30737J24601D01*
G01X1240748Y1505118D02*
G03X1244685Y1509055I0J3937D01*
G01X1240748Y1505118D02*
G03X1244685Y1509055I0J3937D01*
G01X1211220Y1515748D02*
G03X1207283Y1519685I-3937J0D01*
G01X1211220Y1515748D02*
G03X1207283Y1519685I-3937J0D01*
G01X1211220Y1509055D02*
Y1515748D01*
G01Y1509055D02*
G03X1215157Y1505118I3937J0D01*
G01X1240748D02*
X1215157D01*
G01X1211220Y1509055D02*
G03X1215157Y1505118I3937J0D01*
G01D02*
X1240748D01*
G01X1211220Y1515748D02*
Y1509055D01*
G01X1311851Y277843D02*
G03X1318775Y264712I37663J11469D01*
G01X1311850Y277843D02*
G03X1318776Y264712I37661J11473D01*
G01X1311851Y277843D02*
G03X1291890I-9980J-3040D01*
G01X1284965Y264712D02*
G03X1291890Y277843I-30737J24602D01*
G01X1311850D02*
G03X1291890I-9980J-3040D01*
G01X1284965Y264712D02*
G03X1291890Y277843I-30737J24602D01*
G01X1284965Y264712D02*
G03X1318775I16905J-13531D01*
G01X1284965D02*
G03X1318776I16906J-13531D01*
G01X1311851Y730599D02*
G03X1318775Y717468I37663J11469D01*
G01X1311850Y730599D02*
G03X1318776Y717468I37661J11473D01*
G01X1311851Y730599D02*
G03X1291890I-9980J-3040D01*
G01X1284965Y717468D02*
G03X1291891Y730599I-30736J24604D01*
G01X1311850D02*
G03X1291890I-9980J-3040D01*
G01X1284965Y717468D02*
G03X1291890Y730599I-30737J24602D01*
G01X1284965Y717468D02*
G03X1318775I16905J-13531D01*
G01X1284965D02*
G03X1318776I16906J-13531D01*
G01X1284965Y1170224D02*
G03X1318775I16905J-13531D01*
G01X1284965D02*
G03X1318776I16906J-13531D01*
G01X1311851Y1183355D02*
G03X1318775Y1170224I37663J11469D01*
G01X1311850Y1183355D02*
G03X1318776Y1170224I37661J11473D01*
G01X1311851Y1183355D02*
G03X1291890I-9980J-3040D01*
G01X1311850D02*
G03X1291890I-9980J-3040D01*
G01X1284965Y1170224D02*
G03X1291890Y1183355I-30737J24602D01*
G01X1284965Y1170224D02*
G03X1291890Y1183355I-30737J24602D01*
G01X1248622Y1519685D02*
G03X1244685Y1515748I0J-3937D01*
G01X1427953Y1519685D02*
X1248622D01*
G01D02*
G03X1244685Y1515748I0J-3937D01*
G01X1427953Y1519685D02*
X1248622D01*
G01X1244685Y1515748D02*
Y1509055D01*
G01Y1515748D02*
Y1509055D01*
G01X1431890Y1515748D02*
G03X1427953Y1519685I-3937J0D01*
G01X1431890Y1515748D02*
G03X1427953Y1519685I-3937J0D01*
G01X1431890Y1500000D02*
Y1515748D01*
G01Y1500000D02*
G03X1435827Y1496063I3937J0D01*
G01X1431890Y1500000D02*
G03X1435827Y1496063I3937J0D01*
G01X1431890Y1515748D02*
Y1500000D01*
G01X1532996Y264712D02*
G03X1566807I16906J-13531D01*
G01X1532996D02*
G03X1566807I16906J-13531D01*
G01X1532996Y717468D02*
G03X1566807I16906J-13531D01*
G01X1532996D02*
G03X1566807I16906J-13531D01*
G01X1532996Y1170224D02*
G03X1566807I16906J-13531D01*
G01X1532996D02*
G03X1566807I16906J-13531D01*
G01X1469685Y1503937D02*
G03Y1496063I0J-3937D01*
G01X1451575D02*
G03Y1503937I0J3937D01*
G01X1606693D02*
X1469685D01*
G01X1606693D02*
X1469685D01*
G01D02*
G03Y1496063I0J-3937D01*
G01X1451575D02*
G03Y1503937I0J3937D01*
G01X1443701Y1519685D02*
G03X1439764Y1515748I0J-3937D01*
G01X1443701Y1519685D02*
X1632677D01*
G01X1443701D02*
G03X1439764Y1515748I0J-3937D01*
G01X1443701Y1519685D02*
X1632677D01*
G01X1451575Y1503937D02*
X1439764D01*
G01Y1515748D02*
Y1503937D01*
G01X1451575D02*
X1439764D01*
G01X1640551Y1496063D02*
X1435827D01*
G01X1439764Y1515748D02*
Y1503937D01*
G01X1640551Y1496063D02*
X1435827D01*
G01X1559882Y277843D02*
G03X1566807Y264712I37662J11471D01*
G01X1559882Y277843D02*
G03X1539921I-9980J-3040D01*
G01X1559882D02*
G03X1566807Y264712I37662J11471D01*
G01X1559882Y277843D02*
G03X1539921I-9980J-3040D01*
G01X1532996Y264712D02*
G03X1539921Y277843I-30737J24602D01*
G01X1532996Y264712D02*
G03X1539921Y277843I-30737J24602D01*
G01X1559882Y730599D02*
G03X1566807Y717468I37662J11471D01*
G01X1559882Y730599D02*
G03X1539921I-9980J-3040D01*
G01X1559882D02*
G03X1566807Y717468I37662J11471D01*
G01X1559882Y730599D02*
G03X1539921I-9980J-3040D01*
G01X1532996Y717468D02*
G03X1539921Y730599I-30737J24601D01*
G01X1532996Y717468D02*
G03X1539921Y730599I-30737J24601D01*
G01X1559882Y1183355D02*
G03X1539921I-9980J-3040D01*
G01X1559882D02*
G03X1539921I-9980J-3040D01*
G01X1559882D02*
G03X1566807Y1170224I37662J11471D01*
G01X1559882Y1183355D02*
G03X1566807Y1170224I37662J11471D01*
G01X1532996D02*
G03X1539921Y1183355I-30737J24602D01*
G01X1532996Y1170224D02*
G03X1539921Y1183355I-30737J24601D01*
G01X1636614Y1503937D02*
X1624803D01*
G01X1636614D02*
X1624803D01*
G01D02*
G03Y1496063I0J-3937D01*
G01X1606693D02*
G03Y1503937I0J3937D01*
G01X1624803D02*
G03Y1496063I0J-3937D01*
G01X1606693D02*
G03Y1503937I0J3937D01*
G01X1636614Y1515748D02*
G03X1632677Y1519685I-3937J0D01*
G01X1636614Y1515748D02*
G03X1632677Y1519685I-3937J0D01*
G01X1648425D02*
G03X1644488Y1515748I0J-3937D01*
G01X1827756Y1519685D02*
X1648425D01*
G01D02*
G03X1644488Y1515748I0J-3937D01*
G01X1827756Y1519685D02*
X1648425D01*
G01X1636614Y1515748D02*
Y1503937D01*
G01X1640551Y1496063D02*
G03X1644488Y1500000I0J3937D01*
G01Y1515748D02*
Y1500000D01*
G01X1636614Y1515748D02*
Y1503937D01*
G01X1640551Y1496063D02*
G03X1644488Y1500000I0J3937D01*
G01Y1515748D02*
Y1500000D01*
G01X1807914Y277843D02*
G03X1814838Y264712I37663J11469D01*
G01X1807913Y277843D02*
G03X1814839Y264712I37661J11473D01*
G01X1807914Y277843D02*
G03X1787953I-9980J-3040D01*
G01X1781028Y264712D02*
G03X1787953Y277843I-30737J24602D01*
G01X1807913D02*
G03X1787953I-9980J-3040D01*
G01X1781028Y264712D02*
G03X1787953Y277843I-30737J24602D01*
G01X1781028Y264712D02*
G03X1814839I16906J-13531D01*
G01X1781028D02*
G03X1814839I16906J-13531D01*
G01X1807914Y730599D02*
G03X1814838Y717468I37663J11469D01*
G01X1807913Y730599D02*
G03X1814839Y717468I37661J11473D01*
G01X1807914Y730599D02*
G03X1787953I-9980J-3040D01*
G01X1781028Y717468D02*
G03X1787954Y730599I-30736J24604D01*
G01X1807913D02*
G03X1787953I-9980J-3040D01*
G01X1781028Y717468D02*
G03X1787953Y730599I-30737J24602D01*
G01X1781028Y717468D02*
G03X1814838I16905J-13531D01*
G01X1781028D02*
G03X1814839I16906J-13531D01*
G01X1781028Y1170224D02*
G03X1814838I16905J-13531D01*
G01X1781028D02*
G03X1814839I16906J-13531D01*
G01X1807914Y1183355D02*
G03X1814838Y1170224I37662J11468D01*
G01X1807913Y1183355D02*
G03X1814839Y1170224I37661J11473D01*
G01X1807914Y1183355D02*
G03X1787953I-9980J-3040D01*
G01X1807913D02*
G03X1787953I-9980J-3040D01*
G01X1781028Y1170224D02*
G03X1787953Y1183355I-30737J24602D01*
G01X1781028Y1170224D02*
G03X1787953Y1183355I-30737J24602D01*
G01X1869094Y1519685D02*
G03X1865157Y1515748I0J-3937D01*
G01X1919094Y1519685D02*
X1869094D01*
G01D02*
G03X1865157Y1515748I0J-3937D01*
G01X1919094Y1519685D02*
X1869094D01*
G01X1865157Y1515748D02*
Y1509055D01*
G01Y1515748D02*
Y1509055D01*
G01X1861220Y1505118D02*
X1835630D01*
G01X1861220D02*
G03X1865157Y1509055I0J3937D01*
G01X1861220Y1505118D02*
G03X1865157Y1509055I0J3937D01*
G01X1835630Y1505118D02*
X1861220D01*
G01X1831693Y1515748D02*
G03X1827756Y1519685I-3937J0D01*
G01X1831693Y1515748D02*
G03X1827756Y1519685I-3937J0D01*
G01X1831693Y1509055D02*
Y1515748D01*
G01Y1509055D02*
G03X1835630Y1505118I3937J0D01*
G01X1831693Y1509055D02*
G03X1835630Y1505118I3937J0D01*
G01X1831693Y1515748D02*
Y1509055D01*
G01X1930906Y0D02*
G03X1934843Y3937I0J3937D01*
G01X1930906Y0D02*
G03X1934843Y3937I0J3937D01*
G01D02*
Y1456693D01*
G01Y3937D02*
Y1456693D01*
G01X1930906Y1460630D02*
X1926969D01*
G01X1934843Y1456693D02*
G03X1930906Y1460630I-3937J0D01*
G01X1934843Y1456693D02*
G03X1930906Y1460630I-3937J0D01*
G01D02*
X1926969D01*
G01X1923031Y1515748D02*
G03X1919094Y1519685I-3937J0D01*
G01X1923031Y1515748D02*
G03X1919094Y1519685I-3937J0D01*
G01X1923031Y1464567D02*
Y1515748D01*
G01Y1464567D02*
G03X1926969Y1460630I3937J0D01*
G01X1923031Y1464567D02*
G03X1926969Y1460630I3937J0D01*
G01X1923031Y1515748D02*
Y1464567D01*
M02*
